FILE_TYPE = MACRO_DRAWING;
SET COLOR_WIRE YELLOW;
SET COLOR_PROP ORANGE;
SET COLOR_DOT WHITE;
SET COLOR_ARC YELLOW;
SET COLOR_BODY GREEN;
SET COLOR_NOTE PURPLE;
SET PROP_DISPLAY VALUE;
SET PAGE_NUMBER P355;
FORCEADD TAP..1
R 2
(-2350 -550);
FORCEPROP 3 LASTPIN (-2300 -550) SIG_NAME P3E_CPU0_P4_TX_DN<3>
J 0
(-2290 -540);
DISPLAY 0.659574 (-2290 -540);
PAINT MONO (-2290 -540);
DISPLAY INVISIBLE (-2290 -540);
FORCEPROP 1 LASTPIN (-2300 -550) BN 3
J 2
(-2288 -542);
DISPLAY 0.680851 (-2288 -542);
PAINT MONO (-2288 -542);
FORCEPROP 2 LAST CDS_LIB standard
J 0
(-2350 -550);
DISPLAY INVISIBLE (-2350 -550);
FORCEPROP 1 LAST BODY_TYPE PLUMBING
J 2
(-2350 -500);
DISPLAY 0.872340 (-2350 -500);
PAINT GREEN (-2350 -500);
DISPLAY INVISIBLE (-2350 -500);
FORCEPROP 1 LAST HDL_TAP TRUE
J 2
(-2675 -675);
DISPLAY 0.872340 (-2675 -675);
DISPLAY INVISIBLE (-2675 -675);
FORCEPROP 1 LAST PATH I1
J 2
(-2348 -550);
DISPLAY 0.872340 (-2348 -550);
PAINT GREEN (-2348 -550);
DISPLAY INVISIBLE (-2348 -550);
FORCEADD Q_CAP_DIFFBUS..2
R 2
(-1375 -300);
FORCEPROP 1 LAST LOCATION C1991
J 2
(-1150 -300);
DISPLAY 0.723404 (-1150 -300);
PAINT GREEN (-1150 -300);
FORCEPROP 0 LAST $SEC 1
J 0
(-1150 -250);
DISPLAY 0.680851 (-1150 -250);
PAINT MONO (-1150 -250);
DISPLAY INVISIBLE (-1150 -250);
FORCEPROP 0 LAST CDS_SEC 1
J 0
(-1150 -250);
DISPLAY 0.680851 (-1150 -250);
DISPLAY INVISIBLE (-1150 -250);
FORCEPROP 0 LASTPIN (-1300 -300) $PN 1
J 0
(-1290 -290);
DISPLAY 0.680851 (-1290 -290);
PAINT MONO (-1290 -290);
FORCEPROP 0 LASTPIN (-1450 -300) $PN 2
J 2
(-1460 -290);
DISPLAY 0.680851 (-1460 -290);
PAINT MONO (-1460 -290);
FORCEPROP 2 LAST VALUE DIFF BUS_0.22UF
J 2
(-1525 -300);
DISPLAY 0.553191 (-1525 -300);
FORCEPROP 2 LAST CDS_LIB pure_quanta
J 0
(-1375 -300);
DISPLAY INVISIBLE (-1375 -300);
FORCEPROP 1 LAST CDS_LMAN_SYM_OUTLINE -25,50,25,-50
J 2
(-1375 -300);
DISPLAY 0.468085 (-1375 -300);
PAINT GREEN (-1375 -300);
DISPLAY INVISIBLE (-1375 -300);
FORCEPROP 1 LAST PIN_NAMES_ROTATE TRUE
J 2
(-1375 -300);
DISPLAY 0.489362 (-1375 -300);
PAINT GREEN (-1375 -300);
DISPLAY INVISIBLE (-1375 -300);
FORCEPROP 2 LAST VOLTAGE 6.3V
J 2
(-1725 -250);
DISPLAY 0.553191 (-1725 -250);
DISPLAY INVISIBLE (-1725 -250);
FORCEPROP 1 LAST MATERIAL X6S
J 2
(-1366 -221);
DISPLAY 0.574468 (-1366 -221);
PAINT GREEN (-1366 -221);
DISPLAY INVISIBLE (-1366 -221);
FORCEPROP 2 LAST PACK_TYPE C0201
J 2
(-1550 -250);
DISPLAY 0.553191 (-1550 -250);
DISPLAY INVISIBLE (-1550 -250);
FORCEPROP 2 LAST TOLERANCE 20%
J 2
(-1450 -250);
DISPLAY 0.553191 (-1450 -250);
DISPLAY INVISIBLE (-1450 -250);
FORCEPROP 1 LAST PART_NUMBER SP_CH4221MEE01
J 2
(-1491 -212);
DISPLAY 0.574468 (-1491 -212);
PAINT GREEN (-1491 -212);
DISPLAY INVISIBLE (-1491 -212);
FORCEPROP 1 LAST PATH I10
J 2
(-1375 -300);
DISPLAY 0.723404 (-1375 -300);
DISPLAY INVISIBLE (-1375 -300);
FORCEADD TAP..1
(-750 3050);
FORCEPROP 3 LASTPIN (-800 3050) SIG_NAME P5E_CPU1_P3_TX_C_DP<8>
J 0
(-790 3060);
DISPLAY 0.659574 (-790 3060);
PAINT MONO (-790 3060);
DISPLAY INVISIBLE (-790 3060);
FORCEPROP 1 LASTPIN (-800 3050) BN 8
J 0
(-812 3058);
DISPLAY 0.680851 (-812 3058);
PAINT GREEN (-812 3058);
FORCEPROP 2 LAST CDS_LIB standard
J 0
(-750 3050);
DISPLAY INVISIBLE (-750 3050);
FORCEPROP 1 LAST BODY_TYPE PLUMBING
J 0
(-750 3100);
DISPLAY 0.872340 (-750 3100);
PAINT GREEN (-750 3100);
DISPLAY INVISIBLE (-750 3100);
FORCEPROP 1 LAST HDL_TAP TRUE
J 0
(-425 2925);
DISPLAY 0.872340 (-425 2925);
DISPLAY INVISIBLE (-425 2925);
FORCEPROP 1 LAST PATH I100
J 0
(-752 3050);
DISPLAY 0.872340 (-752 3050);
PAINT GREEN (-752 3050);
DISPLAY INVISIBLE (-752 3050);
FORCEADD TAP..1
(-750 3250);
FORCEPROP 3 LASTPIN (-800 3250) SIG_NAME P5E_CPU1_P3_TX_C_DP<9>
J 0
(-790 3260);
DISPLAY 0.659574 (-790 3260);
PAINT MONO (-790 3260);
DISPLAY INVISIBLE (-790 3260);
FORCEPROP 1 LASTPIN (-800 3250) BN 9
J 0
(-812 3258);
DISPLAY 0.680851 (-812 3258);
PAINT GREEN (-812 3258);
FORCEPROP 2 LAST CDS_LIB standard
J 0
(-750 3250);
DISPLAY INVISIBLE (-750 3250);
FORCEPROP 1 LAST BODY_TYPE PLUMBING
J 0
(-750 3300);
DISPLAY 0.872340 (-750 3300);
PAINT GREEN (-750 3300);
DISPLAY INVISIBLE (-750 3300);
FORCEPROP 1 LAST HDL_TAP TRUE
J 0
(-425 3125);
DISPLAY 0.872340 (-425 3125);
DISPLAY INVISIBLE (-425 3125);
FORCEPROP 1 LAST PATH I101
J 0
(-752 3250);
DISPLAY 0.872340 (-752 3250);
PAINT GREEN (-752 3250);
DISPLAY INVISIBLE (-752 3250);
FORCEADD TAP..1
(-750 3450);
FORCEPROP 3 LASTPIN (-800 3450) SIG_NAME P5E_CPU1_P3_TX_C_DP<10>
J 0
(-790 3460);
DISPLAY 0.659574 (-790 3460);
PAINT MONO (-790 3460);
DISPLAY INVISIBLE (-790 3460);
FORCEPROP 1 LASTPIN (-800 3450) BN 10
J 0
(-812 3458);
DISPLAY 0.680851 (-812 3458);
PAINT GREEN (-812 3458);
FORCEPROP 2 LAST CDS_LIB standard
J 0
(-750 3450);
DISPLAY INVISIBLE (-750 3450);
FORCEPROP 1 LAST BODY_TYPE PLUMBING
J 0
(-750 3500);
DISPLAY 0.872340 (-750 3500);
PAINT GREEN (-750 3500);
DISPLAY INVISIBLE (-750 3500);
FORCEPROP 1 LAST HDL_TAP TRUE
J 0
(-425 3325);
DISPLAY 0.872340 (-425 3325);
DISPLAY INVISIBLE (-425 3325);
FORCEPROP 1 LAST PATH I102
J 0
(-752 3450);
DISPLAY 0.872340 (-752 3450);
PAINT GREEN (-752 3450);
DISPLAY INVISIBLE (-752 3450);
FORCEADD TAP..1
(-950 3700);
FORCEPROP 3 LASTPIN (-1000 3700) SIG_NAME P5E_CPU1_P3_TX_C_DN<11>
J 0
(-990 3710);
DISPLAY 0.659574 (-990 3710);
PAINT MONO (-990 3710);
DISPLAY INVISIBLE (-990 3710);
FORCEPROP 1 LASTPIN (-1000 3700) BN 11
J 0
(-1012 3708);
DISPLAY 0.680851 (-1012 3708);
PAINT GREEN (-1012 3708);
FORCEPROP 2 LAST CDS_LIB standard
J 0
(-950 3700);
DISPLAY INVISIBLE (-950 3700);
FORCEPROP 1 LAST BODY_TYPE PLUMBING
J 0
(-950 3750);
DISPLAY 0.872340 (-950 3750);
PAINT GREEN (-950 3750);
DISPLAY INVISIBLE (-950 3750);
FORCEPROP 1 LAST HDL_TAP TRUE
J 0
(-625 3575);
DISPLAY 0.872340 (-625 3575);
DISPLAY INVISIBLE (-625 3575);
FORCEPROP 1 LAST PATH I103
J 0
(-952 3700);
DISPLAY 0.872340 (-952 3700);
PAINT GREEN (-952 3700);
DISPLAY INVISIBLE (-952 3700);
FORCEADD TAP..1
(-950 3900);
FORCEPROP 3 LASTPIN (-1000 3900) SIG_NAME P5E_CPU1_P3_TX_C_DN<12>
J 0
(-990 3910);
DISPLAY 0.659574 (-990 3910);
PAINT MONO (-990 3910);
DISPLAY INVISIBLE (-990 3910);
FORCEPROP 1 LASTPIN (-1000 3900) BN 12
J 0
(-1012 3908);
DISPLAY 0.680851 (-1012 3908);
PAINT GREEN (-1012 3908);
FORCEPROP 2 LAST CDS_LIB standard
J 0
(-950 3900);
DISPLAY INVISIBLE (-950 3900);
FORCEPROP 1 LAST BODY_TYPE PLUMBING
J 0
(-950 3950);
DISPLAY 0.872340 (-950 3950);
PAINT GREEN (-950 3950);
DISPLAY INVISIBLE (-950 3950);
FORCEPROP 1 LAST HDL_TAP TRUE
J 0
(-625 3775);
DISPLAY 0.872340 (-625 3775);
DISPLAY INVISIBLE (-625 3775);
FORCEPROP 1 LAST PATH I104
J 0
(-952 3900);
DISPLAY 0.872340 (-952 3900);
PAINT GREEN (-952 3900);
DISPLAY INVISIBLE (-952 3900);
FORCEADD TAP..1
(-750 3650);
FORCEPROP 3 LASTPIN (-800 3650) SIG_NAME P5E_CPU1_P3_TX_C_DP<11>
J 0
(-790 3660);
DISPLAY 0.659574 (-790 3660);
PAINT MONO (-790 3660);
DISPLAY INVISIBLE (-790 3660);
FORCEPROP 1 LASTPIN (-800 3650) BN 11
J 0
(-812 3658);
DISPLAY 0.680851 (-812 3658);
PAINT GREEN (-812 3658);
FORCEPROP 2 LAST CDS_LIB standard
J 0
(-750 3650);
DISPLAY INVISIBLE (-750 3650);
FORCEPROP 1 LAST BODY_TYPE PLUMBING
J 0
(-750 3700);
DISPLAY 0.872340 (-750 3700);
PAINT GREEN (-750 3700);
DISPLAY INVISIBLE (-750 3700);
FORCEPROP 1 LAST HDL_TAP TRUE
J 0
(-425 3525);
DISPLAY 0.872340 (-425 3525);
DISPLAY INVISIBLE (-425 3525);
FORCEPROP 1 LAST PATH I105
J 0
(-752 3650);
DISPLAY 0.872340 (-752 3650);
PAINT GREEN (-752 3650);
DISPLAY INVISIBLE (-752 3650);
FORCEADD TAP..1
(-750 3850);
FORCEPROP 3 LASTPIN (-800 3850) SIG_NAME P5E_CPU1_P3_TX_C_DP<12>
J 0
(-790 3860);
DISPLAY 0.659574 (-790 3860);
PAINT MONO (-790 3860);
DISPLAY INVISIBLE (-790 3860);
FORCEPROP 1 LASTPIN (-800 3850) BN 12
J 0
(-812 3858);
DISPLAY 0.680851 (-812 3858);
PAINT GREEN (-812 3858);
FORCEPROP 2 LAST CDS_LIB standard
J 0
(-750 3850);
DISPLAY INVISIBLE (-750 3850);
FORCEPROP 1 LAST BODY_TYPE PLUMBING
J 0
(-750 3900);
DISPLAY 0.872340 (-750 3900);
PAINT GREEN (-750 3900);
DISPLAY INVISIBLE (-750 3900);
FORCEPROP 1 LAST HDL_TAP TRUE
J 0
(-425 3725);
DISPLAY 0.872340 (-425 3725);
DISPLAY INVISIBLE (-425 3725);
FORCEPROP 1 LAST PATH I106
J 0
(-752 3850);
DISPLAY 0.872340 (-752 3850);
PAINT GREEN (-752 3850);
DISPLAY INVISIBLE (-752 3850);
FORCEADD Q_CAP_DIFFBUS..2
R 2
(-1500 4050);
FORCEPROP 1 LAST LOCATION C53
J 2
(-1250 4075);
DISPLAY 0.723404 (-1250 4075);
PAINT GREEN (-1250 4075);
FORCEPROP 2 LAST $SEC 1
J 2
(-1325 4125);
DISPLAY 0.680851 (-1325 4125);
PAINT MONO (-1325 4125);
DISPLAY INVISIBLE (-1325 4125);
FORCEPROP 2 LAST CDS_SEC 1
J 2
(-1325 4125);
DISPLAY 0.680851 (-1325 4125);
DISPLAY INVISIBLE (-1325 4125);
FORCEPROP 2 LASTPIN (-1425 4050) $PN 1
J 0
(-1415 4060);
DISPLAY 0.808511 (-1415 4060);
FORCEPROP 2 LASTPIN (-1575 4050) $PN 2
J 2
(-1585 4060);
DISPLAY 0.808511 (-1585 4060);
FORCEPROP 2 LAST VALUE DIFF BUS_0.22UF
J 2
(-1650 4050);
DISPLAY 0.553191 (-1650 4050);
FORCEPROP 1 LAST PIN_NAMES_ROTATE TRUE
J 2
(-1500 4050);
DISPLAY 0.489362 (-1500 4050);
PAINT GREEN (-1500 4050);
DISPLAY INVISIBLE (-1500 4050);
FORCEPROP 2 LAST VOLTAGE 6.3V
J 2
(-1850 4100);
DISPLAY 0.553191 (-1850 4100);
DISPLAY INVISIBLE (-1850 4100);
FORCEPROP 1 LAST MATERIAL X6S
J 2
(-1491 4129);
DISPLAY 0.574468 (-1491 4129);
PAINT GREEN (-1491 4129);
DISPLAY INVISIBLE (-1491 4129);
FORCEPROP 2 LAST PACK_TYPE C0201
J 2
(-1675 4100);
DISPLAY 0.553191 (-1675 4100);
DISPLAY INVISIBLE (-1675 4100);
FORCEPROP 2 LAST TOLERANCE 20%
J 2
(-1575 4100);
DISPLAY 0.553191 (-1575 4100);
DISPLAY INVISIBLE (-1575 4100);
FORCEPROP 1 LAST CDS_LMAN_SYM_OUTLINE -25,50,25,-50
J 2
(-1500 4050);
DISPLAY 0.468085 (-1500 4050);
PAINT GREEN (-1500 4050);
DISPLAY INVISIBLE (-1500 4050);
FORCEPROP 2 LAST CDS_LIB pure_quanta
J 2
(-1500 4050);
DISPLAY INVISIBLE (-1500 4050);
FORCEPROP 1 LAST PART_NUMBER SP_CH4221MEE01
J 2
(-1616 4138);
DISPLAY 0.574468 (-1616 4138);
PAINT GREEN (-1616 4138);
DISPLAY INVISIBLE (-1616 4138);
FORCEPROP 1 LAST PATH I107
J 2
(-1500 4050);
DISPLAY 0.723404 (-1500 4050);
DISPLAY INVISIBLE (-1500 4050);
FORCEADD OFFPAGE..1
(-3425 4475);
FORCEPROP 2 LAST $XR0 52 
J 0
(-3676 4475);
DISPLAY 0.638298 (-3676 4475);
PAINT MONO (-3676 4475);
FORCEPROP 2 LAST CDS_LIB standard
J 0
(-3425 4475);
DISPLAY INVISIBLE (-3425 4475);
FORCEPROP 1 LAST OFFPAGE TRUE
J 0
(-3100 4350);
DISPLAY 0.872340 (-3100 4350);
DISPLAY INVISIBLE (-3100 4350);
FORCEPROP 1 LAST COMMENT_BODY TRUE
J 0
(-3300 4375);
DISPLAY 0.872340 (-3300 4375);
PAINT GREEN (-3300 4375);
DISPLAY INVISIBLE (-3300 4375);
FORCEPROP 2 LAST PATH I108
J 0
(-3675 4525);
DISPLAY 0.680851 (-3675 4525);
DISPLAY INVISIBLE (-3675 4525);
FORCEADD OFFPAGE..1
(-3425 4525);
FORCEPROP 2 LAST $XR0 52 
J 0
(-3676 4525);
DISPLAY 0.638298 (-3676 4525);
PAINT MONO (-3676 4525);
FORCEPROP 2 LAST CDS_LIB standard
J 0
(-3425 4525);
DISPLAY INVISIBLE (-3425 4525);
FORCEPROP 1 LAST OFFPAGE TRUE
J 0
(-3100 4400);
DISPLAY 0.872340 (-3100 4400);
DISPLAY INVISIBLE (-3100 4400);
FORCEPROP 1 LAST COMMENT_BODY TRUE
J 0
(-3300 4425);
DISPLAY 0.872340 (-3300 4425);
PAINT GREEN (-3300 4425);
DISPLAY INVISIBLE (-3300 4425);
FORCEPROP 2 LAST PATH I109
J 0
(-3675 4575);
DISPLAY 0.680851 (-3675 4575);
DISPLAY INVISIBLE (-3675 4575);
FORCEADD Q_CAP_DIFFBUS..2
R 2
(-1375 -150);
FORCEPROP 1 LAST LOCATION C1994
J 2
(-1150 -150);
DISPLAY 0.723404 (-1150 -150);
PAINT GREEN (-1150 -150);
FORCEPROP 0 LAST $SEC 1
J 0
(-1150 -100);
DISPLAY 0.680851 (-1150 -100);
PAINT MONO (-1150 -100);
DISPLAY INVISIBLE (-1150 -100);
FORCEPROP 0 LAST CDS_SEC 1
J 0
(-1150 -100);
DISPLAY 0.680851 (-1150 -100);
DISPLAY INVISIBLE (-1150 -100);
FORCEPROP 0 LASTPIN (-1300 -150) $PN 1
J 0
(-1290 -140);
DISPLAY 0.680851 (-1290 -140);
PAINT MONO (-1290 -140);
FORCEPROP 0 LASTPIN (-1450 -150) $PN 2
J 2
(-1460 -140);
DISPLAY 0.680851 (-1460 -140);
PAINT MONO (-1460 -140);
FORCEPROP 2 LAST VALUE DIFF BUS_0.22UF
J 2
(-1525 -150);
DISPLAY 0.553191 (-1525 -150);
FORCEPROP 2 LAST CDS_LIB pure_quanta
J 0
(-1375 -150);
DISPLAY INVISIBLE (-1375 -150);
FORCEPROP 1 LAST CDS_LMAN_SYM_OUTLINE -25,50,25,-50
J 2
(-1375 -150);
DISPLAY 0.468085 (-1375 -150);
PAINT GREEN (-1375 -150);
DISPLAY INVISIBLE (-1375 -150);
FORCEPROP 1 LAST PIN_NAMES_ROTATE TRUE
J 2
(-1375 -150);
DISPLAY 0.489362 (-1375 -150);
PAINT GREEN (-1375 -150);
DISPLAY INVISIBLE (-1375 -150);
FORCEPROP 2 LAST VOLTAGE 6.3V
J 2
(-1725 -100);
DISPLAY 0.553191 (-1725 -100);
DISPLAY INVISIBLE (-1725 -100);
FORCEPROP 1 LAST MATERIAL X6S
J 2
(-1366 -71);
DISPLAY 0.574468 (-1366 -71);
PAINT GREEN (-1366 -71);
DISPLAY INVISIBLE (-1366 -71);
FORCEPROP 2 LAST PACK_TYPE C0201
J 2
(-1550 -100);
DISPLAY 0.553191 (-1550 -100);
DISPLAY INVISIBLE (-1550 -100);
FORCEPROP 2 LAST TOLERANCE 20%
J 2
(-1450 -100);
DISPLAY 0.553191 (-1450 -100);
DISPLAY INVISIBLE (-1450 -100);
FORCEPROP 1 LAST PART_NUMBER SP_CH4221MEE01
J 2
(-1491 -62);
DISPLAY 0.574468 (-1491 -62);
PAINT GREEN (-1491 -62);
DISPLAY INVISIBLE (-1491 -62);
FORCEPROP 1 LAST PATH I11
J 2
(-1375 -150);
DISPLAY 0.723404 (-1375 -150);
DISPLAY INVISIBLE (-1375 -150);
FORCEADD TAP..1
R 2
(-2475 4250);
FORCEPROP 3 LASTPIN (-2425 4250) SIG_NAME P5E_CPU1_P3_TX_DP<14>
J 0
(-2415 4260);
DISPLAY 0.659574 (-2415 4260);
PAINT MONO (-2415 4260);
DISPLAY INVISIBLE (-2415 4260);
FORCEPROP 1 LASTPIN (-2425 4250) BN 14
J 2
(-2413 4258);
DISPLAY 0.680851 (-2413 4258);
PAINT GREEN (-2413 4258);
FORCEPROP 2 LAST CDS_LIB standard
J 0
(-2475 4250);
DISPLAY INVISIBLE (-2475 4250);
FORCEPROP 1 LAST BODY_TYPE PLUMBING
J 2
(-2475 4300);
DISPLAY 0.872340 (-2475 4300);
PAINT GREEN (-2475 4300);
DISPLAY INVISIBLE (-2475 4300);
FORCEPROP 1 LAST HDL_TAP TRUE
J 2
(-2800 4125);
DISPLAY 0.872340 (-2800 4125);
DISPLAY INVISIBLE (-2800 4125);
FORCEPROP 1 LAST PATH I110
J 2
(-2473 4250);
DISPLAY 0.872340 (-2473 4250);
PAINT GREEN (-2473 4250);
DISPLAY INVISIBLE (-2473 4250);
FORCEADD TAP..1
R 2
(-2475 4050);
FORCEPROP 3 LASTPIN (-2425 4050) SIG_NAME P5E_CPU1_P3_TX_DP<13>
J 0
(-2415 4060);
DISPLAY 0.659574 (-2415 4060);
PAINT MONO (-2415 4060);
DISPLAY INVISIBLE (-2415 4060);
FORCEPROP 1 LASTPIN (-2425 4050) BN 13
J 2
(-2413 4058);
DISPLAY 0.680851 (-2413 4058);
PAINT GREEN (-2413 4058);
FORCEPROP 2 LAST CDS_LIB standard
J 0
(-2475 4050);
DISPLAY INVISIBLE (-2475 4050);
FORCEPROP 1 LAST BODY_TYPE PLUMBING
J 2
(-2475 4100);
DISPLAY 0.872340 (-2475 4100);
PAINT GREEN (-2475 4100);
DISPLAY INVISIBLE (-2475 4100);
FORCEPROP 1 LAST HDL_TAP TRUE
J 2
(-2800 3925);
DISPLAY 0.872340 (-2800 3925);
DISPLAY INVISIBLE (-2800 3925);
FORCEPROP 1 LAST PATH I111
J 2
(-2473 4050);
DISPLAY 0.872340 (-2473 4050);
PAINT GREEN (-2473 4050);
DISPLAY INVISIBLE (-2473 4050);
FORCEADD TAP..1
R 2
(-2475 4450);
FORCEPROP 3 LASTPIN (-2425 4450) SIG_NAME P5E_CPU1_P3_TX_DP<15>
J 0
(-2415 4460);
DISPLAY 0.659574 (-2415 4460);
PAINT MONO (-2415 4460);
DISPLAY INVISIBLE (-2415 4460);
FORCEPROP 1 LASTPIN (-2425 4450) BN 15
J 2
(-2413 4458);
DISPLAY 0.680851 (-2413 4458);
PAINT GREEN (-2413 4458);
FORCEPROP 2 LAST CDS_LIB standard
J 0
(-2475 4450);
DISPLAY INVISIBLE (-2475 4450);
FORCEPROP 1 LAST BODY_TYPE PLUMBING
J 2
(-2475 4500);
DISPLAY 0.872340 (-2475 4500);
PAINT GREEN (-2475 4500);
DISPLAY INVISIBLE (-2475 4500);
FORCEPROP 1 LAST HDL_TAP TRUE
J 2
(-2800 4325);
DISPLAY 0.872340 (-2800 4325);
DISPLAY INVISIBLE (-2800 4325);
FORCEPROP 1 LAST PATH I112
J 2
(-2473 4450);
DISPLAY 0.872340 (-2473 4450);
PAINT GREEN (-2473 4450);
DISPLAY INVISIBLE (-2473 4450);
FORCEADD TAP..1
R 2
(-2225 4100);
FORCEPROP 3 LASTPIN (-2175 4100) SIG_NAME P5E_CPU1_P3_TX_DN<13>
J 0
(-2165 4110);
DISPLAY 0.659574 (-2165 4110);
PAINT MONO (-2165 4110);
DISPLAY INVISIBLE (-2165 4110);
FORCEPROP 1 LASTPIN (-2175 4100) BN 13
J 2
(-2163 4108);
DISPLAY 0.680851 (-2163 4108);
PAINT GREEN (-2163 4108);
FORCEPROP 2 LAST CDS_LIB standard
J 0
(-2225 4100);
DISPLAY INVISIBLE (-2225 4100);
FORCEPROP 1 LAST BODY_TYPE PLUMBING
J 2
(-2225 4150);
DISPLAY 0.872340 (-2225 4150);
PAINT GREEN (-2225 4150);
DISPLAY INVISIBLE (-2225 4150);
FORCEPROP 1 LAST HDL_TAP TRUE
J 2
(-2550 3975);
DISPLAY 0.872340 (-2550 3975);
DISPLAY INVISIBLE (-2550 3975);
FORCEPROP 1 LAST PATH I113
J 2
(-2223 4100);
DISPLAY 0.872340 (-2223 4100);
PAINT GREEN (-2223 4100);
DISPLAY INVISIBLE (-2223 4100);
FORCEADD TAP..1
R 2
(-2225 4500);
FORCEPROP 3 LASTPIN (-2175 4500) SIG_NAME P5E_CPU1_P3_TX_DN<15>
J 0
(-2165 4510);
DISPLAY 0.659574 (-2165 4510);
PAINT MONO (-2165 4510);
DISPLAY INVISIBLE (-2165 4510);
FORCEPROP 1 LASTPIN (-2175 4500) BN 15
J 2
(-2163 4508);
DISPLAY 0.680851 (-2163 4508);
PAINT GREEN (-2163 4508);
FORCEPROP 2 LAST CDS_LIB standard
J 0
(-2225 4500);
DISPLAY INVISIBLE (-2225 4500);
FORCEPROP 1 LAST BODY_TYPE PLUMBING
J 2
(-2225 4550);
DISPLAY 0.872340 (-2225 4550);
PAINT GREEN (-2225 4550);
DISPLAY INVISIBLE (-2225 4550);
FORCEPROP 1 LAST HDL_TAP TRUE
J 2
(-2550 4375);
DISPLAY 0.872340 (-2550 4375);
DISPLAY INVISIBLE (-2550 4375);
FORCEPROP 1 LAST PATH I114
J 2
(-2223 4500);
DISPLAY 0.872340 (-2223 4500);
PAINT GREEN (-2223 4500);
DISPLAY INVISIBLE (-2223 4500);
FORCEADD TAP..1
R 2
(-2225 4300);
FORCEPROP 3 LASTPIN (-2175 4300) SIG_NAME P5E_CPU1_P3_TX_DN<14>
J 0
(-2165 4310);
DISPLAY 0.659574 (-2165 4310);
PAINT MONO (-2165 4310);
DISPLAY INVISIBLE (-2165 4310);
FORCEPROP 1 LASTPIN (-2175 4300) BN 14
J 2
(-2163 4308);
DISPLAY 0.680851 (-2163 4308);
PAINT GREEN (-2163 4308);
FORCEPROP 2 LAST CDS_LIB standard
J 0
(-2225 4300);
DISPLAY INVISIBLE (-2225 4300);
FORCEPROP 1 LAST BODY_TYPE PLUMBING
J 2
(-2225 4350);
DISPLAY 0.872340 (-2225 4350);
PAINT GREEN (-2225 4350);
DISPLAY INVISIBLE (-2225 4350);
FORCEPROP 1 LAST HDL_TAP TRUE
J 2
(-2550 4175);
DISPLAY 0.872340 (-2550 4175);
DISPLAY INVISIBLE (-2550 4175);
FORCEPROP 1 LAST PATH I115
J 2
(-2223 4300);
DISPLAY 0.872340 (-2223 4300);
PAINT GREEN (-2223 4300);
DISPLAY INVISIBLE (-2223 4300);
FORCEADD Q_CAP_DIFFBUS..2
R 2
(-1500 4100);
FORCEPROP 1 LAST LOCATION C52
J 2
(-1250 4125);
DISPLAY 0.723404 (-1250 4125);
PAINT GREEN (-1250 4125);
FORCEPROP 2 LAST $SEC 1
J 2
(-1325 4175);
DISPLAY 0.680851 (-1325 4175);
PAINT MONO (-1325 4175);
DISPLAY INVISIBLE (-1325 4175);
FORCEPROP 2 LAST CDS_SEC 1
J 2
(-1325 4175);
DISPLAY 0.680851 (-1325 4175);
DISPLAY INVISIBLE (-1325 4175);
FORCEPROP 2 LASTPIN (-1425 4100) $PN 1
J 0
(-1415 4110);
DISPLAY 0.808511 (-1415 4110);
FORCEPROP 2 LASTPIN (-1575 4100) $PN 2
J 2
(-1585 4110);
DISPLAY 0.808511 (-1585 4110);
FORCEPROP 2 LAST VALUE DIFF BUS_0.22UF
J 2
(-1650 4100);
DISPLAY 0.553191 (-1650 4100);
FORCEPROP 1 LAST PIN_NAMES_ROTATE TRUE
J 2
(-1500 4100);
DISPLAY 0.489362 (-1500 4100);
PAINT GREEN (-1500 4100);
DISPLAY INVISIBLE (-1500 4100);
FORCEPROP 2 LAST VOLTAGE 6.3V
J 2
(-1850 4150);
DISPLAY 0.553191 (-1850 4150);
DISPLAY INVISIBLE (-1850 4150);
FORCEPROP 1 LAST MATERIAL X6S
J 2
(-1491 4179);
DISPLAY 0.574468 (-1491 4179);
PAINT GREEN (-1491 4179);
DISPLAY INVISIBLE (-1491 4179);
FORCEPROP 2 LAST PACK_TYPE C0201
J 2
(-1675 4150);
DISPLAY 0.553191 (-1675 4150);
DISPLAY INVISIBLE (-1675 4150);
FORCEPROP 2 LAST TOLERANCE 20%
J 2
(-1575 4150);
DISPLAY 0.553191 (-1575 4150);
DISPLAY INVISIBLE (-1575 4150);
FORCEPROP 1 LAST CDS_LMAN_SYM_OUTLINE -25,50,25,-50
J 2
(-1500 4100);
DISPLAY 0.468085 (-1500 4100);
PAINT GREEN (-1500 4100);
DISPLAY INVISIBLE (-1500 4100);
FORCEPROP 2 LAST CDS_LIB pure_quanta
J 2
(-1500 4100);
DISPLAY INVISIBLE (-1500 4100);
FORCEPROP 1 LAST PART_NUMBER SP_CH4221MEE01
J 2
(-1616 4188);
DISPLAY 0.574468 (-1616 4188);
PAINT GREEN (-1616 4188);
DISPLAY INVISIBLE (-1616 4188);
FORCEPROP 1 LAST PATH I116
J 2
(-1500 4100);
DISPLAY 0.723404 (-1500 4100);
DISPLAY INVISIBLE (-1500 4100);
FORCEADD Q_CAP_DIFFBUS..2
R 2
(-1500 4250);
FORCEPROP 1 LAST LOCATION C51
J 2
(-1250 4275);
DISPLAY 0.723404 (-1250 4275);
PAINT GREEN (-1250 4275);
FORCEPROP 2 LAST $SEC 1
J 2
(-1325 4325);
DISPLAY 0.680851 (-1325 4325);
PAINT MONO (-1325 4325);
DISPLAY INVISIBLE (-1325 4325);
FORCEPROP 2 LAST CDS_SEC 1
J 2
(-1325 4325);
DISPLAY 0.680851 (-1325 4325);
DISPLAY INVISIBLE (-1325 4325);
FORCEPROP 2 LASTPIN (-1425 4250) $PN 1
J 0
(-1415 4260);
DISPLAY 0.808511 (-1415 4260);
FORCEPROP 2 LASTPIN (-1575 4250) $PN 2
J 2
(-1585 4260);
DISPLAY 0.808511 (-1585 4260);
FORCEPROP 2 LAST VALUE DIFF BUS_0.22UF
J 2
(-1650 4250);
DISPLAY 0.553191 (-1650 4250);
FORCEPROP 1 LAST PIN_NAMES_ROTATE TRUE
J 2
(-1500 4250);
DISPLAY 0.489362 (-1500 4250);
PAINT GREEN (-1500 4250);
DISPLAY INVISIBLE (-1500 4250);
FORCEPROP 2 LAST VOLTAGE 6.3V
J 2
(-1850 4300);
DISPLAY 0.553191 (-1850 4300);
DISPLAY INVISIBLE (-1850 4300);
FORCEPROP 1 LAST MATERIAL X6S
J 2
(-1491 4329);
DISPLAY 0.574468 (-1491 4329);
PAINT GREEN (-1491 4329);
DISPLAY INVISIBLE (-1491 4329);
FORCEPROP 2 LAST PACK_TYPE C0201
J 2
(-1675 4300);
DISPLAY 0.553191 (-1675 4300);
DISPLAY INVISIBLE (-1675 4300);
FORCEPROP 2 LAST TOLERANCE 20%
J 2
(-1575 4300);
DISPLAY 0.553191 (-1575 4300);
DISPLAY INVISIBLE (-1575 4300);
FORCEPROP 1 LAST CDS_LMAN_SYM_OUTLINE -25,50,25,-50
J 2
(-1500 4250);
DISPLAY 0.468085 (-1500 4250);
PAINT GREEN (-1500 4250);
DISPLAY INVISIBLE (-1500 4250);
FORCEPROP 2 LAST CDS_LIB pure_quanta
J 2
(-1500 4250);
DISPLAY INVISIBLE (-1500 4250);
FORCEPROP 1 LAST PART_NUMBER SP_CH4221MEE01
J 2
(-1616 4338);
DISPLAY 0.574468 (-1616 4338);
PAINT GREEN (-1616 4338);
DISPLAY INVISIBLE (-1616 4338);
FORCEPROP 1 LAST PATH I117
J 2
(-1500 4250);
DISPLAY 0.723404 (-1500 4250);
DISPLAY INVISIBLE (-1500 4250);
FORCEADD Q_CAP_DIFFBUS..2
R 2
(-1500 4300);
FORCEPROP 1 LAST LOCATION C50
J 2
(-1250 4325);
DISPLAY 0.723404 (-1250 4325);
PAINT GREEN (-1250 4325);
FORCEPROP 2 LAST $SEC 1
J 2
(-1325 4375);
DISPLAY 0.680851 (-1325 4375);
PAINT MONO (-1325 4375);
DISPLAY INVISIBLE (-1325 4375);
FORCEPROP 2 LAST CDS_SEC 1
J 2
(-1325 4375);
DISPLAY 0.680851 (-1325 4375);
DISPLAY INVISIBLE (-1325 4375);
FORCEPROP 2 LASTPIN (-1425 4300) $PN 1
J 0
(-1415 4310);
DISPLAY 0.808511 (-1415 4310);
FORCEPROP 2 LASTPIN (-1575 4300) $PN 2
J 2
(-1585 4310);
DISPLAY 0.808511 (-1585 4310);
FORCEPROP 2 LAST VALUE DIFF BUS_0.22UF
J 2
(-1650 4300);
DISPLAY 0.553191 (-1650 4300);
FORCEPROP 1 LAST PIN_NAMES_ROTATE TRUE
J 2
(-1500 4300);
DISPLAY 0.489362 (-1500 4300);
PAINT GREEN (-1500 4300);
DISPLAY INVISIBLE (-1500 4300);
FORCEPROP 2 LAST VOLTAGE 6.3V
J 2
(-1850 4350);
DISPLAY 0.553191 (-1850 4350);
DISPLAY INVISIBLE (-1850 4350);
FORCEPROP 1 LAST MATERIAL X6S
J 2
(-1491 4379);
DISPLAY 0.574468 (-1491 4379);
PAINT GREEN (-1491 4379);
DISPLAY INVISIBLE (-1491 4379);
FORCEPROP 2 LAST PACK_TYPE C0201
J 2
(-1675 4350);
DISPLAY 0.553191 (-1675 4350);
DISPLAY INVISIBLE (-1675 4350);
FORCEPROP 2 LAST TOLERANCE 20%
J 2
(-1575 4350);
DISPLAY 0.553191 (-1575 4350);
DISPLAY INVISIBLE (-1575 4350);
FORCEPROP 1 LAST CDS_LMAN_SYM_OUTLINE -25,50,25,-50
J 2
(-1500 4300);
DISPLAY 0.468085 (-1500 4300);
PAINT GREEN (-1500 4300);
DISPLAY INVISIBLE (-1500 4300);
FORCEPROP 2 LAST CDS_LIB pure_quanta
J 2
(-1500 4300);
DISPLAY INVISIBLE (-1500 4300);
FORCEPROP 1 LAST PART_NUMBER SP_CH4221MEE01
J 2
(-1616 4388);
DISPLAY 0.574468 (-1616 4388);
PAINT GREEN (-1616 4388);
DISPLAY INVISIBLE (-1616 4388);
FORCEPROP 1 LAST PATH I118
J 2
(-1500 4300);
DISPLAY 0.723404 (-1500 4300);
DISPLAY INVISIBLE (-1500 4300);
FORCEADD Q_CAP_DIFFBUS..2
R 2
(-1500 4500);
FORCEPROP 1 LAST LOCATION C48
J 2
(-1250 4525);
DISPLAY 0.723404 (-1250 4525);
PAINT GREEN (-1250 4525);
FORCEPROP 2 LAST $SEC 1
J 2
(-1325 4575);
DISPLAY 0.680851 (-1325 4575);
PAINT MONO (-1325 4575);
DISPLAY INVISIBLE (-1325 4575);
FORCEPROP 2 LAST CDS_SEC 1
J 2
(-1325 4575);
DISPLAY 0.680851 (-1325 4575);
DISPLAY INVISIBLE (-1325 4575);
FORCEPROP 2 LASTPIN (-1425 4500) $PN 1
J 0
(-1415 4510);
DISPLAY 0.808511 (-1415 4510);
FORCEPROP 2 LASTPIN (-1575 4500) $PN 2
J 2
(-1585 4510);
DISPLAY 0.808511 (-1585 4510);
FORCEPROP 2 LAST VOLTAGE 6.3V
J 2
(-1250 4650);
DISPLAY 0.553191 (-1250 4650);
PAINT GREEN (-1250 4650);
FORCEPROP 2 LAST TOLERANCE 20%
J 2
(-1400 4650);
DISPLAY 0.553191 (-1400 4650);
PAINT GREEN (-1400 4650);
FORCEPROP 1 LAST MATERIAL X6S
J 2
(-1541 4704);
DISPLAY 0.574468 (-1541 4704);
PAINT GREEN (-1541 4704);
FORCEPROP 2 LAST PACK_TYPE C0201
J 2
(-1500 4650);
DISPLAY 0.553191 (-1500 4650);
PAINT GREEN (-1500 4650);
FORCEPROP 2 LAST VALUE DIFF BUS_0.22UF
J 2
(-1650 4500);
DISPLAY 0.553191 (-1650 4500);
FORCEPROP 1 LAST PIN_NAMES_ROTATE TRUE
J 2
(-1500 4500);
DISPLAY 0.489362 (-1500 4500);
PAINT GREEN (-1500 4500);
DISPLAY INVISIBLE (-1500 4500);
FORCEPROP 2 LAST CDS_LIB pure_quanta
J 2
(-1500 4500);
DISPLAY INVISIBLE (-1500 4500);
FORCEPROP 1 LAST CDS_LMAN_SYM_OUTLINE -25,50,25,-50
J 2
(-1500 4500);
DISPLAY 0.468085 (-1500 4500);
PAINT GREEN (-1500 4500);
DISPLAY INVISIBLE (-1500 4500);
FORCEPROP 1 LAST PART_NUMBER SP_CH4221MEE01
J 2
(-1241 4588);
DISPLAY 0.574468 (-1241 4588);
PAINT GREEN (-1241 4588);
DISPLAY INVISIBLE (-1241 4588);
FORCEPROP 1 LAST PATH I119
J 2
(-1500 4500);
DISPLAY 0.723404 (-1500 4500);
DISPLAY INVISIBLE (-1500 4500);
FORCEADD Q_CAP_DIFFBUS..2
R 2
(-1375 -100);
FORCEPROP 1 LAST LOCATION C1993
J 2
(-1150 -100);
DISPLAY 0.723404 (-1150 -100);
PAINT GREEN (-1150 -100);
FORCEPROP 0 LAST $SEC 1
J 0
(-1150 -50);
DISPLAY 0.680851 (-1150 -50);
PAINT MONO (-1150 -50);
DISPLAY INVISIBLE (-1150 -50);
FORCEPROP 0 LAST CDS_SEC 1
J 0
(-1150 -50);
DISPLAY 0.680851 (-1150 -50);
DISPLAY INVISIBLE (-1150 -50);
FORCEPROP 0 LASTPIN (-1300 -100) $PN 1
J 0
(-1290 -90);
DISPLAY 0.680851 (-1290 -90);
PAINT MONO (-1290 -90);
FORCEPROP 0 LASTPIN (-1450 -100) $PN 2
J 2
(-1460 -90);
DISPLAY 0.680851 (-1460 -90);
PAINT MONO (-1460 -90);
FORCEPROP 2 LAST VALUE DIFF BUS_0.22UF
J 2
(-1525 -100);
DISPLAY 0.553191 (-1525 -100);
FORCEPROP 2 LAST CDS_LIB pure_quanta
J 0
(-1375 -100);
DISPLAY INVISIBLE (-1375 -100);
FORCEPROP 1 LAST CDS_LMAN_SYM_OUTLINE -25,50,25,-50
J 2
(-1375 -100);
DISPLAY 0.468085 (-1375 -100);
PAINT GREEN (-1375 -100);
DISPLAY INVISIBLE (-1375 -100);
FORCEPROP 1 LAST PIN_NAMES_ROTATE TRUE
J 2
(-1375 -100);
DISPLAY 0.489362 (-1375 -100);
PAINT GREEN (-1375 -100);
DISPLAY INVISIBLE (-1375 -100);
FORCEPROP 2 LAST VOLTAGE 6.3V
J 2
(-1725 -50);
DISPLAY 0.553191 (-1725 -50);
DISPLAY INVISIBLE (-1725 -50);
FORCEPROP 1 LAST MATERIAL X6S
J 2
(-1366 -21);
DISPLAY 0.574468 (-1366 -21);
PAINT GREEN (-1366 -21);
DISPLAY INVISIBLE (-1366 -21);
FORCEPROP 2 LAST PACK_TYPE C0201
J 2
(-1550 -50);
DISPLAY 0.553191 (-1550 -50);
DISPLAY INVISIBLE (-1550 -50);
FORCEPROP 2 LAST TOLERANCE 20%
J 2
(-1450 -50);
DISPLAY 0.553191 (-1450 -50);
DISPLAY INVISIBLE (-1450 -50);
FORCEPROP 1 LAST PART_NUMBER SP_CH4221MEE01
J 2
(-1491 -12);
DISPLAY 0.574468 (-1491 -12);
PAINT GREEN (-1491 -12);
DISPLAY INVISIBLE (-1491 -12);
FORCEPROP 1 LAST PATH I12
J 2
(-1375 -100);
DISPLAY 0.723404 (-1375 -100);
DISPLAY INVISIBLE (-1375 -100);
FORCEADD Q_CAP_DIFFBUS..2
R 2
(-1500 4450);
FORCEPROP 1 LAST LOCATION C49
J 2
(-1250 4475);
DISPLAY 0.723404 (-1250 4475);
PAINT GREEN (-1250 4475);
FORCEPROP 2 LAST $SEC 1
J 2
(-1325 4525);
DISPLAY 0.680851 (-1325 4525);
PAINT MONO (-1325 4525);
DISPLAY INVISIBLE (-1325 4525);
FORCEPROP 2 LAST CDS_SEC 1
J 2
(-1325 4525);
DISPLAY 0.680851 (-1325 4525);
DISPLAY INVISIBLE (-1325 4525);
FORCEPROP 2 LASTPIN (-1425 4450) $PN 1
J 0
(-1415 4460);
DISPLAY 0.808511 (-1415 4460);
FORCEPROP 2 LASTPIN (-1575 4450) $PN 2
J 2
(-1585 4460);
DISPLAY 0.808511 (-1585 4460);
FORCEPROP 2 LAST VALUE DIFF BUS_0.22UF
J 2
(-1650 4450);
DISPLAY 0.553191 (-1650 4450);
FORCEPROP 1 LAST PIN_NAMES_ROTATE TRUE
J 2
(-1500 4450);
DISPLAY 0.489362 (-1500 4450);
PAINT GREEN (-1500 4450);
DISPLAY INVISIBLE (-1500 4450);
FORCEPROP 2 LAST VOLTAGE 6.3V
J 2
(-1850 4500);
DISPLAY 0.553191 (-1850 4500);
DISPLAY INVISIBLE (-1850 4500);
FORCEPROP 1 LAST MATERIAL X6S
J 2
(-1491 4529);
DISPLAY 0.574468 (-1491 4529);
PAINT GREEN (-1491 4529);
DISPLAY INVISIBLE (-1491 4529);
FORCEPROP 2 LAST PACK_TYPE C0201
J 2
(-1675 4500);
DISPLAY 0.553191 (-1675 4500);
DISPLAY INVISIBLE (-1675 4500);
FORCEPROP 2 LAST TOLERANCE 20%
J 2
(-1575 4500);
DISPLAY 0.553191 (-1575 4500);
DISPLAY INVISIBLE (-1575 4500);
FORCEPROP 1 LAST CDS_LMAN_SYM_OUTLINE -25,50,25,-50
J 2
(-1500 4450);
DISPLAY 0.468085 (-1500 4450);
PAINT GREEN (-1500 4450);
DISPLAY INVISIBLE (-1500 4450);
FORCEPROP 2 LAST CDS_LIB pure_quanta
J 2
(-1500 4450);
DISPLAY INVISIBLE (-1500 4450);
FORCEPROP 1 LAST PART_NUMBER SP_CH4221MEE01
J 2
(-1616 4538);
DISPLAY 0.574468 (-1616 4538);
PAINT GREEN (-1616 4538);
DISPLAY INVISIBLE (-1616 4538);
FORCEPROP 1 LAST PATH I120
J 2
(-1500 4450);
DISPLAY 0.723404 (-1500 4450);
DISPLAY INVISIBLE (-1500 4450);
FORCEADD TAP..1
(-950 4100);
FORCEPROP 3 LASTPIN (-1000 4100) SIG_NAME P5E_CPU1_P3_TX_C_DN<13>
J 0
(-990 4110);
DISPLAY 0.659574 (-990 4110);
PAINT MONO (-990 4110);
DISPLAY INVISIBLE (-990 4110);
FORCEPROP 1 LASTPIN (-1000 4100) BN 13
J 0
(-1012 4108);
DISPLAY 0.680851 (-1012 4108);
PAINT GREEN (-1012 4108);
FORCEPROP 2 LAST CDS_LIB standard
J 0
(-950 4100);
DISPLAY INVISIBLE (-950 4100);
FORCEPROP 1 LAST BODY_TYPE PLUMBING
J 0
(-950 4150);
DISPLAY 0.872340 (-950 4150);
PAINT GREEN (-950 4150);
DISPLAY INVISIBLE (-950 4150);
FORCEPROP 1 LAST HDL_TAP TRUE
J 0
(-625 3975);
DISPLAY 0.872340 (-625 3975);
DISPLAY INVISIBLE (-625 3975);
FORCEPROP 1 LAST PATH I121
J 0
(-952 4100);
DISPLAY 0.872340 (-952 4100);
PAINT GREEN (-952 4100);
DISPLAY INVISIBLE (-952 4100);
FORCEADD TAP..1
(-950 4500);
FORCEPROP 3 LASTPIN (-1000 4500) SIG_NAME P5E_CPU1_P3_TX_C_DN<15>
J 0
(-990 4510);
DISPLAY 0.659574 (-990 4510);
PAINT MONO (-990 4510);
DISPLAY INVISIBLE (-990 4510);
FORCEPROP 1 LASTPIN (-1000 4500) BN 15
J 0
(-1012 4508);
DISPLAY 0.680851 (-1012 4508);
PAINT GREEN (-1012 4508);
FORCEPROP 2 LAST CDS_LIB standard
J 0
(-950 4500);
DISPLAY INVISIBLE (-950 4500);
FORCEPROP 1 LAST BODY_TYPE PLUMBING
J 0
(-950 4550);
DISPLAY 0.872340 (-950 4550);
PAINT GREEN (-950 4550);
DISPLAY INVISIBLE (-950 4550);
FORCEPROP 1 LAST HDL_TAP TRUE
J 0
(-625 4375);
DISPLAY 0.872340 (-625 4375);
DISPLAY INVISIBLE (-625 4375);
FORCEPROP 1 LAST PATH I122
J 0
(-952 4500);
DISPLAY 0.872340 (-952 4500);
PAINT GREEN (-952 4500);
DISPLAY INVISIBLE (-952 4500);
FORCEADD TAP..1
(-950 4300);
FORCEPROP 3 LASTPIN (-1000 4300) SIG_NAME P5E_CPU1_P3_TX_C_DN<14>
J 0
(-990 4310);
DISPLAY 0.659574 (-990 4310);
PAINT MONO (-990 4310);
DISPLAY INVISIBLE (-990 4310);
FORCEPROP 1 LASTPIN (-1000 4300) BN 14
J 0
(-1012 4308);
DISPLAY 0.680851 (-1012 4308);
PAINT GREEN (-1012 4308);
FORCEPROP 2 LAST CDS_LIB standard
J 0
(-950 4300);
DISPLAY INVISIBLE (-950 4300);
FORCEPROP 1 LAST BODY_TYPE PLUMBING
J 0
(-950 4350);
DISPLAY 0.872340 (-950 4350);
PAINT GREEN (-950 4350);
DISPLAY INVISIBLE (-950 4350);
FORCEPROP 1 LAST HDL_TAP TRUE
J 0
(-625 4175);
DISPLAY 0.872340 (-625 4175);
DISPLAY INVISIBLE (-625 4175);
FORCEPROP 1 LAST PATH I123
J 0
(-952 4300);
DISPLAY 0.872340 (-952 4300);
PAINT GREEN (-952 4300);
DISPLAY INVISIBLE (-952 4300);
FORCEADD TAP..1
(-750 4050);
FORCEPROP 3 LASTPIN (-800 4050) SIG_NAME P5E_CPU1_P3_TX_C_DP<13>
J 0
(-790 4060);
DISPLAY 0.659574 (-790 4060);
PAINT MONO (-790 4060);
DISPLAY INVISIBLE (-790 4060);
FORCEPROP 1 LASTPIN (-800 4050) BN 13
J 0
(-812 4058);
DISPLAY 0.680851 (-812 4058);
PAINT GREEN (-812 4058);
FORCEPROP 2 LAST CDS_LIB standard
J 0
(-750 4050);
DISPLAY INVISIBLE (-750 4050);
FORCEPROP 1 LAST BODY_TYPE PLUMBING
J 0
(-750 4100);
DISPLAY 0.872340 (-750 4100);
PAINT GREEN (-750 4100);
DISPLAY INVISIBLE (-750 4100);
FORCEPROP 1 LAST HDL_TAP TRUE
J 0
(-425 3925);
DISPLAY 0.872340 (-425 3925);
DISPLAY INVISIBLE (-425 3925);
FORCEPROP 1 LAST PATH I124
J 0
(-752 4050);
DISPLAY 0.872340 (-752 4050);
PAINT GREEN (-752 4050);
DISPLAY INVISIBLE (-752 4050);
FORCEADD TAP..1
(-750 4250);
FORCEPROP 3 LASTPIN (-800 4250) SIG_NAME P5E_CPU1_P3_TX_C_DP<14>
J 0
(-790 4260);
DISPLAY 0.659574 (-790 4260);
PAINT MONO (-790 4260);
DISPLAY INVISIBLE (-790 4260);
FORCEPROP 1 LASTPIN (-800 4250) BN 14
J 0
(-812 4258);
DISPLAY 0.680851 (-812 4258);
PAINT GREEN (-812 4258);
FORCEPROP 2 LAST CDS_LIB standard
J 0
(-750 4250);
DISPLAY INVISIBLE (-750 4250);
FORCEPROP 1 LAST BODY_TYPE PLUMBING
J 0
(-750 4300);
DISPLAY 0.872340 (-750 4300);
PAINT GREEN (-750 4300);
DISPLAY INVISIBLE (-750 4300);
FORCEPROP 1 LAST HDL_TAP TRUE
J 0
(-425 4125);
DISPLAY 0.872340 (-425 4125);
DISPLAY INVISIBLE (-425 4125);
FORCEPROP 1 LAST PATH I125
J 0
(-752 4250);
DISPLAY 0.872340 (-752 4250);
PAINT GREEN (-752 4250);
DISPLAY INVISIBLE (-752 4250);
FORCEADD TAP..1
(-750 4450);
FORCEPROP 3 LASTPIN (-800 4450) SIG_NAME P5E_CPU1_P3_TX_C_DP<15>
J 0
(-790 4460);
DISPLAY 0.659574 (-790 4460);
PAINT MONO (-790 4460);
DISPLAY INVISIBLE (-790 4460);
FORCEPROP 1 LASTPIN (-800 4450) BN 15
J 0
(-812 4458);
DISPLAY 0.680851 (-812 4458);
PAINT GREEN (-812 4458);
FORCEPROP 2 LAST CDS_LIB standard
J 0
(-750 4450);
DISPLAY INVISIBLE (-750 4450);
FORCEPROP 1 LAST BODY_TYPE PLUMBING
J 0
(-750 4500);
DISPLAY 0.872340 (-750 4500);
PAINT GREEN (-750 4500);
DISPLAY INVISIBLE (-750 4500);
FORCEPROP 1 LAST HDL_TAP TRUE
J 0
(-425 4325);
DISPLAY 0.872340 (-425 4325);
DISPLAY INVISIBLE (-425 4325);
FORCEPROP 1 LAST PATH I126
J 0
(-752 4450);
DISPLAY 0.872340 (-752 4450);
PAINT GREEN (-752 4450);
DISPLAY INVISIBLE (-752 4450);
FORCEADD TAP..1
R 2
(2175 -625);
FORCEPROP 3 LASTPIN (2225 -625) SIG_NAME P3E_CPU1_P4_TX_DN<3>
J 0
(2235 -615);
DISPLAY 0.659574 (2235 -615);
PAINT MONO (2235 -615);
DISPLAY INVISIBLE (2235 -615);
FORCEPROP 1 LASTPIN (2225 -625) BN 3
J 2
(2237 -617);
DISPLAY 0.680851 (2237 -617);
PAINT MONO (2237 -617);
FORCEPROP 2 LAST CDS_LIB standard
J 0
(2175 -625);
DISPLAY INVISIBLE (2175 -625);
FORCEPROP 1 LAST BODY_TYPE PLUMBING
J 2
(2175 -575);
DISPLAY 0.872340 (2175 -575);
PAINT GREEN (2175 -575);
DISPLAY INVISIBLE (2175 -575);
FORCEPROP 1 LAST HDL_TAP TRUE
J 2
(1850 -750);
DISPLAY 0.872340 (1850 -750);
DISPLAY INVISIBLE (1850 -750);
FORCEPROP 1 LAST PATH I127
J 2
(2177 -625);
DISPLAY 0.872340 (2177 -625);
PAINT GREEN (2177 -625);
DISPLAY INVISIBLE (2177 -625);
FORCEADD TAP..1
R 2
(2175 -425);
FORCEPROP 3 LASTPIN (2225 -425) SIG_NAME P3E_CPU1_P4_TX_DN<2>
J 0
(2235 -415);
DISPLAY 0.659574 (2235 -415);
PAINT MONO (2235 -415);
DISPLAY INVISIBLE (2235 -415);
FORCEPROP 1 LASTPIN (2225 -425) BN 2
J 2
(2237 -417);
DISPLAY 0.680851 (2237 -417);
PAINT MONO (2237 -417);
FORCEPROP 2 LAST CDS_LIB standard
J 0
(2175 -425);
DISPLAY INVISIBLE (2175 -425);
FORCEPROP 1 LAST BODY_TYPE PLUMBING
J 2
(2175 -375);
DISPLAY 0.872340 (2175 -375);
PAINT GREEN (2175 -375);
DISPLAY INVISIBLE (2175 -375);
FORCEPROP 1 LAST HDL_TAP TRUE
J 2
(1850 -550);
DISPLAY 0.872340 (1850 -550);
DISPLAY INVISIBLE (1850 -550);
FORCEPROP 1 LAST PATH I128
J 2
(2177 -425);
DISPLAY 0.872340 (2177 -425);
PAINT GREEN (2177 -425);
DISPLAY INVISIBLE (2177 -425);
FORCEADD TAP..1
R 2
(2175 -225);
FORCEPROP 3 LASTPIN (2225 -225) SIG_NAME P3E_CPU1_P4_TX_DN<1>
J 0
(2235 -215);
DISPLAY 0.659574 (2235 -215);
PAINT MONO (2235 -215);
DISPLAY INVISIBLE (2235 -215);
FORCEPROP 1 LASTPIN (2225 -225) BN 1
J 2
(2237 -217);
DISPLAY 0.680851 (2237 -217);
PAINT MONO (2237 -217);
FORCEPROP 2 LAST CDS_LIB standard
J 0
(2175 -225);
DISPLAY INVISIBLE (2175 -225);
FORCEPROP 1 LAST BODY_TYPE PLUMBING
J 2
(2175 -175);
DISPLAY 0.872340 (2175 -175);
PAINT GREEN (2175 -175);
DISPLAY INVISIBLE (2175 -175);
FORCEPROP 1 LAST HDL_TAP TRUE
J 2
(1850 -350);
DISPLAY 0.872340 (1850 -350);
DISPLAY INVISIBLE (1850 -350);
FORCEPROP 1 LAST PATH I129
J 2
(2177 -225);
DISPLAY 0.872340 (2177 -225);
PAINT GREEN (2177 -225);
DISPLAY INVISIBLE (2177 -225);
FORCEADD TAP..1
(-825 -500);
FORCEPROP 3 LASTPIN (-875 -500) SIG_NAME P3E_CPU0_P4_TX_C_DP<3>
J 0
(-865 -490);
DISPLAY 0.659574 (-865 -490);
PAINT MONO (-865 -490);
DISPLAY INVISIBLE (-865 -490);
FORCEPROP 1 LASTPIN (-875 -500) BN 3
J 0
(-887 -492);
DISPLAY 0.680851 (-887 -492);
PAINT MONO (-887 -492);
FORCEPROP 2 LAST CDS_LIB standard
J 0
(-825 -500);
DISPLAY INVISIBLE (-825 -500);
FORCEPROP 1 LAST BODY_TYPE PLUMBING
J 0
(-825 -450);
DISPLAY 0.872340 (-825 -450);
PAINT GREEN (-825 -450);
DISPLAY INVISIBLE (-825 -450);
FORCEPROP 1 LAST HDL_TAP TRUE
J 0
(-500 -625);
DISPLAY 0.872340 (-500 -625);
DISPLAY INVISIBLE (-500 -625);
FORCEPROP 1 LAST PATH I13
J 0
(-827 -500);
DISPLAY 0.872340 (-827 -500);
PAINT GREEN (-827 -500);
DISPLAY INVISIBLE (-827 -500);
FORCEADD TAP..1
R 2
(2425 -575);
FORCEPROP 3 LASTPIN (2475 -575) SIG_NAME P3E_CPU1_P4_TX_DP<3>
J 0
(2485 -565);
DISPLAY 0.659574 (2485 -565);
PAINT MONO (2485 -565);
DISPLAY INVISIBLE (2485 -565);
FORCEPROP 1 LASTPIN (2475 -575) BN 3
J 2
(2487 -567);
DISPLAY 0.680851 (2487 -567);
PAINT MONO (2487 -567);
FORCEPROP 2 LAST CDS_LIB standard
J 0
(2425 -575);
DISPLAY INVISIBLE (2425 -575);
FORCEPROP 1 LAST BODY_TYPE PLUMBING
J 2
(2425 -525);
DISPLAY 0.872340 (2425 -525);
PAINT GREEN (2425 -525);
DISPLAY INVISIBLE (2425 -525);
FORCEPROP 1 LAST HDL_TAP TRUE
J 2
(2100 -700);
DISPLAY 0.872340 (2100 -700);
DISPLAY INVISIBLE (2100 -700);
FORCEPROP 1 LAST PATH I130
J 2
(2427 -575);
DISPLAY 0.872340 (2427 -575);
PAINT GREEN (2427 -575);
DISPLAY INVISIBLE (2427 -575);
FORCEADD TAP..1
R 2
(2425 -375);
FORCEPROP 3 LASTPIN (2475 -375) SIG_NAME P3E_CPU1_P4_TX_DP<2>
J 0
(2485 -365);
DISPLAY 0.659574 (2485 -365);
PAINT MONO (2485 -365);
DISPLAY INVISIBLE (2485 -365);
FORCEPROP 1 LASTPIN (2475 -375) BN 2
J 2
(2487 -367);
DISPLAY 0.680851 (2487 -367);
PAINT MONO (2487 -367);
FORCEPROP 2 LAST CDS_LIB standard
J 0
(2425 -375);
DISPLAY INVISIBLE (2425 -375);
FORCEPROP 1 LAST BODY_TYPE PLUMBING
J 2
(2425 -325);
DISPLAY 0.872340 (2425 -325);
PAINT GREEN (2425 -325);
DISPLAY INVISIBLE (2425 -325);
FORCEPROP 1 LAST HDL_TAP TRUE
J 2
(2100 -500);
DISPLAY 0.872340 (2100 -500);
DISPLAY INVISIBLE (2100 -500);
FORCEPROP 1 LAST PATH I131
J 2
(2427 -375);
DISPLAY 0.872340 (2427 -375);
PAINT GREEN (2427 -375);
DISPLAY INVISIBLE (2427 -375);
FORCEADD TAP..1
R 2
(2425 -175);
FORCEPROP 3 LASTPIN (2475 -175) SIG_NAME P3E_CPU1_P4_TX_DP<1>
J 0
(2485 -165);
DISPLAY 0.659574 (2485 -165);
PAINT MONO (2485 -165);
DISPLAY INVISIBLE (2485 -165);
FORCEPROP 1 LASTPIN (2475 -175) BN 1
J 2
(2487 -167);
DISPLAY 0.680851 (2487 -167);
PAINT MONO (2487 -167);
FORCEPROP 2 LAST CDS_LIB standard
J 0
(2425 -175);
DISPLAY INVISIBLE (2425 -175);
FORCEPROP 1 LAST BODY_TYPE PLUMBING
J 2
(2425 -125);
DISPLAY 0.872340 (2425 -125);
PAINT GREEN (2425 -125);
DISPLAY INVISIBLE (2425 -125);
FORCEPROP 1 LAST HDL_TAP TRUE
J 2
(2100 -300);
DISPLAY 0.872340 (2100 -300);
DISPLAY INVISIBLE (2100 -300);
FORCEPROP 1 LAST PATH I132
J 2
(2427 -175);
DISPLAY 0.872340 (2427 -175);
PAINT GREEN (2427 -175);
DISPLAY INVISIBLE (2427 -175);
FORCEADD Q_CAP_DIFFBUS..2
R 2
(3150 -625);
FORCEPROP 1 LAST LOCATION C1099
J 2
(3375 -625);
DISPLAY 0.723404 (3375 -625);
PAINT GREEN (3375 -625);
FORCEPROP 0 LAST $SEC 1
J 0
(3375 -575);
DISPLAY 0.680851 (3375 -575);
PAINT MONO (3375 -575);
DISPLAY INVISIBLE (3375 -575);
FORCEPROP 0 LAST CDS_SEC 1
J 0
(3375 -575);
DISPLAY 0.680851 (3375 -575);
DISPLAY INVISIBLE (3375 -575);
FORCEPROP 0 LASTPIN (3225 -625) $PN 1
J 0
(3235 -615);
DISPLAY 0.680851 (3235 -615);
PAINT MONO (3235 -615);
FORCEPROP 0 LASTPIN (3075 -625) $PN 2
J 2
(3065 -615);
DISPLAY 0.680851 (3065 -615);
PAINT MONO (3065 -615);
FORCEPROP 2 LAST VALUE DIFF BUS_0.22UF
J 2
(3000 -625);
DISPLAY 0.553191 (3000 -625);
FORCEPROP 1 LAST PIN_NAMES_ROTATE TRUE
J 2
(3150 -625);
DISPLAY 0.489362 (3150 -625);
PAINT GREEN (3150 -625);
DISPLAY INVISIBLE (3150 -625);
FORCEPROP 2 LAST VOLTAGE 6.3V
J 2
(2800 -575);
DISPLAY 0.553191 (2800 -575);
DISPLAY INVISIBLE (2800 -575);
FORCEPROP 1 LAST MATERIAL X6S
J 2
(3159 -546);
DISPLAY 0.574468 (3159 -546);
PAINT GREEN (3159 -546);
DISPLAY INVISIBLE (3159 -546);
FORCEPROP 2 LAST PACK_TYPE C0201
J 2
(2975 -575);
DISPLAY 0.553191 (2975 -575);
DISPLAY INVISIBLE (2975 -575);
FORCEPROP 2 LAST TOLERANCE 20%
J 2
(3075 -575);
DISPLAY 0.553191 (3075 -575);
DISPLAY INVISIBLE (3075 -575);
FORCEPROP 1 LAST CDS_LMAN_SYM_OUTLINE -25,50,25,-50
J 2
(3150 -625);
DISPLAY 0.468085 (3150 -625);
PAINT GREEN (3150 -625);
DISPLAY INVISIBLE (3150 -625);
FORCEPROP 2 LAST CDS_LIB pure_quanta
J 0
(3150 -625);
DISPLAY INVISIBLE (3150 -625);
FORCEPROP 1 LAST PART_NUMBER SP_CH4221MEE01
J 2
(3034 -537);
DISPLAY 0.574468 (3034 -537);
PAINT GREEN (3034 -537);
DISPLAY INVISIBLE (3034 -537);
FORCEPROP 1 LAST PATH I133
J 2
(3150 -625);
DISPLAY 0.723404 (3150 -625);
DISPLAY INVISIBLE (3150 -625);
FORCEADD Q_CAP_DIFFBUS..2
R 2
(3150 -575);
FORCEPROP 1 LAST LOCATION C1098
J 2
(3375 -575);
DISPLAY 0.723404 (3375 -575);
PAINT GREEN (3375 -575);
FORCEPROP 0 LAST $SEC 1
J 0
(3375 -525);
DISPLAY 0.680851 (3375 -525);
PAINT MONO (3375 -525);
DISPLAY INVISIBLE (3375 -525);
FORCEPROP 0 LAST CDS_SEC 1
J 0
(3375 -525);
DISPLAY 0.680851 (3375 -525);
DISPLAY INVISIBLE (3375 -525);
FORCEPROP 0 LASTPIN (3225 -575) $PN 1
J 0
(3235 -565);
DISPLAY 0.680851 (3235 -565);
PAINT MONO (3235 -565);
FORCEPROP 0 LASTPIN (3075 -575) $PN 2
J 2
(3065 -565);
DISPLAY 0.680851 (3065 -565);
PAINT MONO (3065 -565);
FORCEPROP 2 LAST VALUE DIFF BUS_0.22UF
J 2
(3000 -575);
DISPLAY 0.553191 (3000 -575);
FORCEPROP 2 LAST TOLERANCE 20%
J 2
(3075 -525);
DISPLAY 0.553191 (3075 -525);
DISPLAY INVISIBLE (3075 -525);
FORCEPROP 2 LAST PACK_TYPE C0201
J 2
(2975 -525);
DISPLAY 0.553191 (2975 -525);
DISPLAY INVISIBLE (2975 -525);
FORCEPROP 1 LAST MATERIAL X6S
J 2
(3159 -496);
DISPLAY 0.574468 (3159 -496);
PAINT GREEN (3159 -496);
DISPLAY INVISIBLE (3159 -496);
FORCEPROP 2 LAST VOLTAGE 6.3V
J 2
(2800 -525);
DISPLAY 0.553191 (2800 -525);
DISPLAY INVISIBLE (2800 -525);
FORCEPROP 1 LAST PIN_NAMES_ROTATE TRUE
J 2
(3150 -575);
DISPLAY 0.489362 (3150 -575);
PAINT GREEN (3150 -575);
DISPLAY INVISIBLE (3150 -575);
FORCEPROP 1 LAST CDS_LMAN_SYM_OUTLINE -25,50,25,-50
J 2
(3150 -575);
DISPLAY 0.468085 (3150 -575);
PAINT GREEN (3150 -575);
DISPLAY INVISIBLE (3150 -575);
FORCEPROP 2 LAST CDS_LIB pure_quanta
J 0
(3150 -575);
DISPLAY INVISIBLE (3150 -575);
FORCEPROP 1 LAST PART_NUMBER SP_CH4221MEE01
J 2
(3034 -487);
DISPLAY 0.574468 (3034 -487);
PAINT GREEN (3034 -487);
DISPLAY INVISIBLE (3034 -487);
FORCEPROP 1 LAST PATH I134
J 2
(3150 -575);
DISPLAY 0.723404 (3150 -575);
DISPLAY INVISIBLE (3150 -575);
FORCEADD Q_CAP_DIFFBUS..2
R 2
(3150 -425);
FORCEPROP 1 LAST LOCATION C1101
J 2
(3400 -425);
DISPLAY 0.723404 (3400 -425);
PAINT GREEN (3400 -425);
FORCEPROP 0 LAST $SEC 1
J 0
(3400 -375);
DISPLAY 0.680851 (3400 -375);
PAINT MONO (3400 -375);
DISPLAY INVISIBLE (3400 -375);
FORCEPROP 0 LAST CDS_SEC 1
J 0
(3400 -375);
DISPLAY 0.680851 (3400 -375);
DISPLAY INVISIBLE (3400 -375);
FORCEPROP 0 LASTPIN (3225 -425) $PN 1
J 0
(3235 -415);
DISPLAY 0.680851 (3235 -415);
PAINT MONO (3235 -415);
FORCEPROP 0 LASTPIN (3075 -425) $PN 2
J 2
(3065 -415);
DISPLAY 0.680851 (3065 -415);
PAINT MONO (3065 -415);
FORCEPROP 2 LAST VALUE DIFF BUS_0.22UF
J 2
(3000 -425);
DISPLAY 0.553191 (3000 -425);
FORCEPROP 2 LAST TOLERANCE 20%
J 2
(3075 -375);
DISPLAY 0.553191 (3075 -375);
DISPLAY INVISIBLE (3075 -375);
FORCEPROP 2 LAST PACK_TYPE C0201
J 2
(2975 -375);
DISPLAY 0.553191 (2975 -375);
DISPLAY INVISIBLE (2975 -375);
FORCEPROP 1 LAST MATERIAL X6S
J 2
(3159 -346);
DISPLAY 0.574468 (3159 -346);
PAINT GREEN (3159 -346);
DISPLAY INVISIBLE (3159 -346);
FORCEPROP 2 LAST VOLTAGE 6.3V
J 2
(2800 -375);
DISPLAY 0.553191 (2800 -375);
DISPLAY INVISIBLE (2800 -375);
FORCEPROP 1 LAST PIN_NAMES_ROTATE TRUE
J 2
(3150 -425);
DISPLAY 0.489362 (3150 -425);
PAINT GREEN (3150 -425);
DISPLAY INVISIBLE (3150 -425);
FORCEPROP 1 LAST CDS_LMAN_SYM_OUTLINE -25,50,25,-50
J 2
(3150 -425);
DISPLAY 0.468085 (3150 -425);
PAINT GREEN (3150 -425);
DISPLAY INVISIBLE (3150 -425);
FORCEPROP 2 LAST CDS_LIB pure_quanta
J 0
(3150 -425);
DISPLAY INVISIBLE (3150 -425);
FORCEPROP 1 LAST PART_NUMBER SP_CH4221MEE01
J 2
(3034 -337);
DISPLAY 0.574468 (3034 -337);
PAINT GREEN (3034 -337);
DISPLAY INVISIBLE (3034 -337);
FORCEPROP 1 LAST PATH I135
J 2
(3150 -425);
DISPLAY 0.723404 (3150 -425);
DISPLAY INVISIBLE (3150 -425);
FORCEADD Q_CAP_DIFFBUS..2
R 2
(3150 -375);
FORCEPROP 1 LAST LOCATION C1100
J 2
(3375 -375);
DISPLAY 0.723404 (3375 -375);
PAINT GREEN (3375 -375);
FORCEPROP 0 LAST $SEC 1
J 0
(3375 -325);
DISPLAY 0.680851 (3375 -325);
PAINT MONO (3375 -325);
DISPLAY INVISIBLE (3375 -325);
FORCEPROP 0 LAST CDS_SEC 1
J 0
(3375 -325);
DISPLAY 0.680851 (3375 -325);
DISPLAY INVISIBLE (3375 -325);
FORCEPROP 0 LASTPIN (3225 -375) $PN 1
J 0
(3235 -365);
DISPLAY 0.680851 (3235 -365);
PAINT MONO (3235 -365);
FORCEPROP 0 LASTPIN (3075 -375) $PN 2
J 2
(3065 -365);
DISPLAY 0.680851 (3065 -365);
PAINT MONO (3065 -365);
FORCEPROP 2 LAST VALUE DIFF BUS_0.22UF
J 2
(3000 -375);
DISPLAY 0.553191 (3000 -375);
FORCEPROP 2 LAST TOLERANCE 20%
J 2
(3075 -325);
DISPLAY 0.553191 (3075 -325);
DISPLAY INVISIBLE (3075 -325);
FORCEPROP 2 LAST PACK_TYPE C0201
J 2
(2975 -325);
DISPLAY 0.553191 (2975 -325);
DISPLAY INVISIBLE (2975 -325);
FORCEPROP 1 LAST MATERIAL X6S
J 2
(3159 -296);
DISPLAY 0.574468 (3159 -296);
PAINT GREEN (3159 -296);
DISPLAY INVISIBLE (3159 -296);
FORCEPROP 2 LAST VOLTAGE 6.3V
J 2
(2800 -325);
DISPLAY 0.553191 (2800 -325);
DISPLAY INVISIBLE (2800 -325);
FORCEPROP 1 LAST PIN_NAMES_ROTATE TRUE
J 2
(3150 -375);
DISPLAY 0.489362 (3150 -375);
PAINT GREEN (3150 -375);
DISPLAY INVISIBLE (3150 -375);
FORCEPROP 1 LAST CDS_LMAN_SYM_OUTLINE -25,50,25,-50
J 2
(3150 -375);
DISPLAY 0.468085 (3150 -375);
PAINT GREEN (3150 -375);
DISPLAY INVISIBLE (3150 -375);
FORCEPROP 2 LAST CDS_LIB pure_quanta
J 0
(3150 -375);
DISPLAY INVISIBLE (3150 -375);
FORCEPROP 1 LAST PART_NUMBER SP_CH4221MEE01
J 2
(3034 -287);
DISPLAY 0.574468 (3034 -287);
PAINT GREEN (3034 -287);
DISPLAY INVISIBLE (3034 -287);
FORCEPROP 1 LAST PATH I136
J 2
(3150 -375);
DISPLAY 0.723404 (3150 -375);
DISPLAY INVISIBLE (3150 -375);
FORCEADD Q_CAP_DIFFBUS..2
R 2
(3150 -225);
FORCEPROP 1 LAST LOCATION C9103
J 2
(3400 -225);
DISPLAY 0.723404 (3400 -225);
PAINT GREEN (3400 -225);
FORCEPROP 0 LAST $SEC 1
J 0
(3400 -175);
DISPLAY 0.680851 (3400 -175);
PAINT MONO (3400 -175);
DISPLAY INVISIBLE (3400 -175);
FORCEPROP 0 LAST CDS_SEC 1
J 0
(3400 -175);
DISPLAY 0.680851 (3400 -175);
DISPLAY INVISIBLE (3400 -175);
FORCEPROP 0 LASTPIN (3225 -225) $PN 1
J 0
(3235 -215);
DISPLAY 0.680851 (3235 -215);
PAINT MONO (3235 -215);
FORCEPROP 0 LASTPIN (3075 -225) $PN 2
J 2
(3065 -215);
DISPLAY 0.680851 (3065 -215);
PAINT MONO (3065 -215);
FORCEPROP 2 LAST VALUE DIFF BUS_0.22UF
J 2
(3000 -225);
DISPLAY 0.553191 (3000 -225);
FORCEPROP 2 LAST TOLERANCE 20%
J 2
(3075 -175);
DISPLAY 0.553191 (3075 -175);
DISPLAY INVISIBLE (3075 -175);
FORCEPROP 2 LAST PACK_TYPE C0201
J 2
(2975 -175);
DISPLAY 0.553191 (2975 -175);
DISPLAY INVISIBLE (2975 -175);
FORCEPROP 1 LAST MATERIAL X6S
J 2
(3159 -146);
DISPLAY 0.574468 (3159 -146);
PAINT GREEN (3159 -146);
DISPLAY INVISIBLE (3159 -146);
FORCEPROP 2 LAST VOLTAGE 6.3V
J 2
(2800 -175);
DISPLAY 0.553191 (2800 -175);
DISPLAY INVISIBLE (2800 -175);
FORCEPROP 1 LAST PIN_NAMES_ROTATE TRUE
J 2
(3150 -225);
DISPLAY 0.489362 (3150 -225);
PAINT GREEN (3150 -225);
DISPLAY INVISIBLE (3150 -225);
FORCEPROP 1 LAST CDS_LMAN_SYM_OUTLINE -25,50,25,-50
J 2
(3150 -225);
DISPLAY 0.468085 (3150 -225);
PAINT GREEN (3150 -225);
DISPLAY INVISIBLE (3150 -225);
FORCEPROP 2 LAST CDS_LIB pure_quanta
J 0
(3150 -225);
DISPLAY INVISIBLE (3150 -225);
FORCEPROP 1 LAST PART_NUMBER SP_CH4221MEE01
J 2
(3034 -137);
DISPLAY 0.574468 (3034 -137);
PAINT GREEN (3034 -137);
DISPLAY INVISIBLE (3034 -137);
FORCEPROP 1 LAST PATH I137
J 2
(3150 -225);
DISPLAY 0.723404 (3150 -225);
DISPLAY INVISIBLE (3150 -225);
FORCEADD Q_CAP_DIFFBUS..2
R 2
(3150 -175);
FORCEPROP 1 LAST LOCATION C9102
J 2
(3375 -175);
DISPLAY 0.723404 (3375 -175);
PAINT GREEN (3375 -175);
FORCEPROP 0 LAST $SEC 1
J 0
(3375 -125);
DISPLAY 0.680851 (3375 -125);
PAINT MONO (3375 -125);
DISPLAY INVISIBLE (3375 -125);
FORCEPROP 0 LAST CDS_SEC 1
J 0
(3375 -125);
DISPLAY 0.680851 (3375 -125);
DISPLAY INVISIBLE (3375 -125);
FORCEPROP 0 LASTPIN (3225 -175) $PN 1
J 0
(3235 -165);
DISPLAY 0.680851 (3235 -165);
PAINT MONO (3235 -165);
FORCEPROP 0 LASTPIN (3075 -175) $PN 2
J 2
(3065 -165);
DISPLAY 0.680851 (3065 -165);
PAINT MONO (3065 -165);
FORCEPROP 2 LAST VALUE DIFF BUS_0.22UF
J 2
(3000 -175);
DISPLAY 0.553191 (3000 -175);
FORCEPROP 2 LAST TOLERANCE 20%
J 2
(3075 -125);
DISPLAY 0.553191 (3075 -125);
DISPLAY INVISIBLE (3075 -125);
FORCEPROP 2 LAST PACK_TYPE C0201
J 2
(2975 -125);
DISPLAY 0.553191 (2975 -125);
DISPLAY INVISIBLE (2975 -125);
FORCEPROP 1 LAST MATERIAL X6S
J 2
(3159 -96);
DISPLAY 0.574468 (3159 -96);
PAINT GREEN (3159 -96);
DISPLAY INVISIBLE (3159 -96);
FORCEPROP 2 LAST VOLTAGE 6.3V
J 2
(2800 -125);
DISPLAY 0.553191 (2800 -125);
DISPLAY INVISIBLE (2800 -125);
FORCEPROP 1 LAST PIN_NAMES_ROTATE TRUE
J 2
(3150 -175);
DISPLAY 0.489362 (3150 -175);
PAINT GREEN (3150 -175);
DISPLAY INVISIBLE (3150 -175);
FORCEPROP 1 LAST CDS_LMAN_SYM_OUTLINE -25,50,25,-50
J 2
(3150 -175);
DISPLAY 0.468085 (3150 -175);
PAINT GREEN (3150 -175);
DISPLAY INVISIBLE (3150 -175);
FORCEPROP 2 LAST CDS_LIB pure_quanta
J 0
(3150 -175);
DISPLAY INVISIBLE (3150 -175);
FORCEPROP 1 LAST PART_NUMBER SP_CH4221MEE01
J 2
(3034 -87);
DISPLAY 0.574468 (3034 -87);
PAINT GREEN (3034 -87);
DISPLAY INVISIBLE (3034 -87);
FORCEPROP 1 LAST PATH I138
J 2
(3150 -175);
DISPLAY 0.723404 (3150 -175);
DISPLAY INVISIBLE (3150 -175);
FORCEADD TAP..1
(3900 -625);
FORCEPROP 3 LASTPIN (3850 -625) SIG_NAME P3E_CPU1_P4_TX_C_DN<3>
J 0
(3860 -615);
DISPLAY 0.659574 (3860 -615);
PAINT MONO (3860 -615);
DISPLAY INVISIBLE (3860 -615);
FORCEPROP 1 LASTPIN (3850 -625) BN 3
J 0
(3838 -617);
DISPLAY 0.680851 (3838 -617);
PAINT MONO (3838 -617);
FORCEPROP 2 LAST CDS_LIB standard
J 0
(3900 -625);
DISPLAY INVISIBLE (3900 -625);
FORCEPROP 1 LAST BODY_TYPE PLUMBING
J 0
(3900 -575);
DISPLAY 0.872340 (3900 -575);
PAINT GREEN (3900 -575);
DISPLAY INVISIBLE (3900 -575);
FORCEPROP 1 LAST HDL_TAP TRUE
J 0
(4225 -750);
DISPLAY 0.872340 (4225 -750);
DISPLAY INVISIBLE (4225 -750);
FORCEPROP 1 LAST PATH I139
J 0
(3898 -625);
DISPLAY 0.872340 (3898 -625);
PAINT GREEN (3898 -625);
DISPLAY INVISIBLE (3898 -625);
FORCEADD TAP..1
(-825 -300);
FORCEPROP 3 LASTPIN (-875 -300) SIG_NAME P3E_CPU0_P4_TX_C_DP<2>
J 0
(-865 -290);
DISPLAY 0.659574 (-865 -290);
PAINT MONO (-865 -290);
DISPLAY INVISIBLE (-865 -290);
FORCEPROP 1 LASTPIN (-875 -300) BN 2
J 0
(-887 -292);
DISPLAY 0.680851 (-887 -292);
PAINT MONO (-887 -292);
FORCEPROP 2 LAST CDS_LIB standard
J 0
(-825 -300);
DISPLAY INVISIBLE (-825 -300);
FORCEPROP 1 LAST BODY_TYPE PLUMBING
J 0
(-825 -250);
DISPLAY 0.872340 (-825 -250);
PAINT GREEN (-825 -250);
DISPLAY INVISIBLE (-825 -250);
FORCEPROP 1 LAST HDL_TAP TRUE
J 0
(-500 -425);
DISPLAY 0.872340 (-500 -425);
DISPLAY INVISIBLE (-500 -425);
FORCEPROP 1 LAST PATH I14
J 0
(-827 -300);
DISPLAY 0.872340 (-827 -300);
PAINT GREEN (-827 -300);
DISPLAY INVISIBLE (-827 -300);
FORCEADD TAP..1
(3700 -575);
FORCEPROP 3 LASTPIN (3650 -575) SIG_NAME P3E_CPU1_P4_TX_C_DP<3>
J 0
(3660 -565);
DISPLAY 0.659574 (3660 -565);
PAINT MONO (3660 -565);
DISPLAY INVISIBLE (3660 -565);
FORCEPROP 1 LASTPIN (3650 -575) BN 3
J 0
(3638 -567);
DISPLAY 0.680851 (3638 -567);
PAINT MONO (3638 -567);
FORCEPROP 2 LAST CDS_LIB standard
J 0
(3700 -575);
DISPLAY INVISIBLE (3700 -575);
FORCEPROP 1 LAST BODY_TYPE PLUMBING
J 0
(3700 -525);
DISPLAY 0.872340 (3700 -525);
PAINT GREEN (3700 -525);
DISPLAY INVISIBLE (3700 -525);
FORCEPROP 1 LAST HDL_TAP TRUE
J 0
(4025 -700);
DISPLAY 0.872340 (4025 -700);
DISPLAY INVISIBLE (4025 -700);
FORCEPROP 1 LAST PATH I140
J 0
(3698 -575);
DISPLAY 0.872340 (3698 -575);
PAINT GREEN (3698 -575);
DISPLAY INVISIBLE (3698 -575);
FORCEADD TAP..1
(3700 -375);
FORCEPROP 3 LASTPIN (3650 -375) SIG_NAME P3E_CPU1_P4_TX_C_DP<2>
J 0
(3660 -365);
DISPLAY 0.659574 (3660 -365);
PAINT MONO (3660 -365);
DISPLAY INVISIBLE (3660 -365);
FORCEPROP 1 LASTPIN (3650 -375) BN 2
J 0
(3638 -367);
DISPLAY 0.680851 (3638 -367);
PAINT MONO (3638 -367);
FORCEPROP 2 LAST CDS_LIB standard
J 0
(3700 -375);
DISPLAY INVISIBLE (3700 -375);
FORCEPROP 1 LAST BODY_TYPE PLUMBING
J 0
(3700 -325);
DISPLAY 0.872340 (3700 -325);
PAINT GREEN (3700 -325);
DISPLAY INVISIBLE (3700 -325);
FORCEPROP 1 LAST HDL_TAP TRUE
J 0
(4025 -500);
DISPLAY 0.872340 (4025 -500);
DISPLAY INVISIBLE (4025 -500);
FORCEPROP 1 LAST PATH I141
J 0
(3698 -375);
DISPLAY 0.872340 (3698 -375);
PAINT GREEN (3698 -375);
DISPLAY INVISIBLE (3698 -375);
FORCEADD TAP..1
(3700 -175);
FORCEPROP 3 LASTPIN (3650 -175) SIG_NAME P3E_CPU1_P4_TX_C_DP<1>
J 0
(3660 -165);
DISPLAY 0.659574 (3660 -165);
PAINT MONO (3660 -165);
DISPLAY INVISIBLE (3660 -165);
FORCEPROP 1 LASTPIN (3650 -175) BN 1
J 0
(3638 -167);
DISPLAY 0.680851 (3638 -167);
PAINT MONO (3638 -167);
FORCEPROP 2 LAST CDS_LIB standard
J 0
(3700 -175);
DISPLAY INVISIBLE (3700 -175);
FORCEPROP 1 LAST BODY_TYPE PLUMBING
J 0
(3700 -125);
DISPLAY 0.872340 (3700 -125);
PAINT GREEN (3700 -125);
DISPLAY INVISIBLE (3700 -125);
FORCEPROP 1 LAST HDL_TAP TRUE
J 0
(4025 -300);
DISPLAY 0.872340 (4025 -300);
DISPLAY INVISIBLE (4025 -300);
FORCEPROP 1 LAST PATH I142
J 0
(3698 -175);
DISPLAY 0.872340 (3698 -175);
PAINT GREEN (3698 -175);
DISPLAY INVISIBLE (3698 -175);
FORCEADD TAP..1
(3900 -425);
FORCEPROP 3 LASTPIN (3850 -425) SIG_NAME P3E_CPU1_P4_TX_C_DN<2>
J 0
(3860 -415);
DISPLAY 0.659574 (3860 -415);
PAINT MONO (3860 -415);
DISPLAY INVISIBLE (3860 -415);
FORCEPROP 1 LASTPIN (3850 -425) BN 2
J 0
(3838 -417);
DISPLAY 0.680851 (3838 -417);
PAINT MONO (3838 -417);
FORCEPROP 2 LAST CDS_LIB standard
J 0
(3900 -425);
DISPLAY INVISIBLE (3900 -425);
FORCEPROP 1 LAST BODY_TYPE PLUMBING
J 0
(3900 -375);
DISPLAY 0.872340 (3900 -375);
PAINT GREEN (3900 -375);
DISPLAY INVISIBLE (3900 -375);
FORCEPROP 1 LAST HDL_TAP TRUE
J 0
(4225 -550);
DISPLAY 0.872340 (4225 -550);
DISPLAY INVISIBLE (4225 -550);
FORCEPROP 1 LAST PATH I143
J 0
(3898 -425);
DISPLAY 0.872340 (3898 -425);
PAINT GREEN (3898 -425);
DISPLAY INVISIBLE (3898 -425);
FORCEADD TAP..1
(3900 -225);
FORCEPROP 3 LASTPIN (3850 -225) SIG_NAME P3E_CPU1_P4_TX_C_DN<1>
J 0
(3860 -215);
DISPLAY 0.659574 (3860 -215);
PAINT MONO (3860 -215);
DISPLAY INVISIBLE (3860 -215);
FORCEPROP 1 LASTPIN (3850 -225) BN 1
J 0
(3838 -217);
DISPLAY 0.680851 (3838 -217);
PAINT MONO (3838 -217);
FORCEPROP 2 LAST CDS_LIB standard
J 0
(3900 -225);
DISPLAY INVISIBLE (3900 -225);
FORCEPROP 1 LAST BODY_TYPE PLUMBING
J 0
(3900 -175);
DISPLAY 0.872340 (3900 -175);
PAINT GREEN (3900 -175);
DISPLAY INVISIBLE (3900 -175);
FORCEPROP 1 LAST HDL_TAP TRUE
J 0
(4225 -350);
DISPLAY 0.872340 (4225 -350);
DISPLAY INVISIBLE (4225 -350);
FORCEPROP 1 LAST PATH I144
J 0
(3898 -225);
DISPLAY 0.872340 (3898 -225);
PAINT GREEN (3898 -225);
DISPLAY INVISIBLE (3898 -225);
FORCEADD OFFPAGE..2
(375 75);
FORCEPROP 2 LAST $XR0 145 
J 0
(564 75);
DISPLAY 0.638298 (564 75);
PAINT MONO (564 75);
FORCEPROP 2 LAST CDS_LIB standard
J 0
(375 75);
DISPLAY INVISIBLE (375 75);
FORCEPROP 1 LAST OFFPAGE TRUE
J 0
(700 -50);
DISPLAY 0.872340 (700 -50);
DISPLAY INVISIBLE (700 -50);
FORCEPROP 1 LAST COMMENT_BODY TRUE
J 0
(330 -20);
DISPLAY 0.872340 (330 -20);
PAINT GREEN (330 -20);
DISPLAY INVISIBLE (330 -20);
FORCEPROP 2 LAST PATH I145
J 0
(550 150);
DISPLAY 0.680851 (550 150);
DISPLAY INVISIBLE (550 150);
FORCEADD OFFPAGE..2
(375 125);
FORCEPROP 2 LAST $XR0 145 
J 0
(564 125);
DISPLAY 0.638298 (564 125);
PAINT MONO (564 125);
FORCEPROP 2 LAST CDS_LIB standard
J 0
(375 125);
DISPLAY INVISIBLE (375 125);
FORCEPROP 1 LAST OFFPAGE TRUE
J 0
(700 0);
DISPLAY 0.872340 (700 0);
DISPLAY INVISIBLE (700 0);
FORCEPROP 1 LAST COMMENT_BODY TRUE
J 0
(330 30);
DISPLAY 0.872340 (330 30);
PAINT GREEN (330 30);
DISPLAY INVISIBLE (330 30);
FORCEPROP 2 LAST PATH I146
J 0
(550 200);
DISPLAY 0.680851 (550 200);
DISPLAY INVISIBLE (550 200);
FORCEADD OFFPAGE..1
(1225 0);
FORCEPROP 2 LAST $XR0 53 
J 0
(1004 0);
DISPLAY 0.638298 (1004 0);
PAINT MONO (1004 0);
FORCEPROP 2 LAST CDS_LIB standard
J 0
(1225 0);
DISPLAY INVISIBLE (1225 0);
FORCEPROP 1 LAST OFFPAGE TRUE
J 0
(1550 -125);
DISPLAY 0.872340 (1550 -125);
DISPLAY INVISIBLE (1550 -125);
FORCEPROP 1 LAST COMMENT_BODY TRUE
J 0
(1350 -100);
DISPLAY 0.872340 (1350 -100);
PAINT GREEN (1350 -100);
DISPLAY INVISIBLE (1350 -100);
FORCEPROP 2 LAST PATH I147
J 0
(1275 75);
DISPLAY 0.680851 (1275 75);
DISPLAY INVISIBLE (1275 75);
FORCEADD OFFPAGE..1
(1225 50);
FORCEPROP 2 LAST $XR0 53 
J 0
(1004 50);
DISPLAY 0.638298 (1004 50);
PAINT MONO (1004 50);
FORCEPROP 2 LAST CDS_LIB standard
J 0
(1225 50);
DISPLAY INVISIBLE (1225 50);
FORCEPROP 1 LAST OFFPAGE TRUE
J 0
(1550 -75);
DISPLAY 0.872340 (1550 -75);
DISPLAY INVISIBLE (1550 -75);
FORCEPROP 1 LAST COMMENT_BODY TRUE
J 0
(1350 -50);
DISPLAY 0.872340 (1350 -50);
PAINT GREEN (1350 -50);
DISPLAY INVISIBLE (1350 -50);
FORCEPROP 2 LAST PATH I148
J 0
(1275 125);
DISPLAY 0.680851 (1275 125);
DISPLAY INVISIBLE (1275 125);
FORCEADD OFFPAGE..2
(225 2850);
FORCEPROP 2 LAST $XR0 350 
J 0
(414 2850);
DISPLAY 0.638298 (414 2850);
PAINT MONO (414 2850);
FORCEPROP 2 LAST CDS_LIB standard
J 0
(225 2850);
DISPLAY INVISIBLE (225 2850);
FORCEPROP 1 LAST OFFPAGE TRUE
J 0
(550 2725);
DISPLAY 0.872340 (550 2725);
DISPLAY INVISIBLE (550 2725);
FORCEPROP 1 LAST COMMENT_BODY TRUE
J 0
(180 2755);
DISPLAY 0.872340 (180 2755);
PAINT GREEN (180 2755);
DISPLAY INVISIBLE (180 2755);
FORCEPROP 2 LAST PATH I149
J 0
(425 2900);
DISPLAY 0.680851 (425 2900);
DISPLAY INVISIBLE (425 2900);
FORCEADD TAP..1
(-825 -100);
FORCEPROP 3 LASTPIN (-875 -100) SIG_NAME P3E_CPU0_P4_TX_C_DP<1>
J 0
(-865 -90);
DISPLAY 0.659574 (-865 -90);
PAINT MONO (-865 -90);
DISPLAY INVISIBLE (-865 -90);
FORCEPROP 1 LASTPIN (-875 -100) BN 1
J 0
(-887 -92);
DISPLAY 0.680851 (-887 -92);
PAINT MONO (-887 -92);
FORCEPROP 2 LAST CDS_LIB standard
J 0
(-825 -100);
DISPLAY INVISIBLE (-825 -100);
FORCEPROP 1 LAST BODY_TYPE PLUMBING
J 0
(-825 -50);
DISPLAY 0.872340 (-825 -50);
PAINT GREEN (-825 -50);
DISPLAY INVISIBLE (-825 -50);
FORCEPROP 1 LAST HDL_TAP TRUE
J 0
(-500 -225);
DISPLAY 0.872340 (-500 -225);
DISPLAY INVISIBLE (-500 -225);
FORCEPROP 1 LAST PATH I15
J 0
(-827 -100);
DISPLAY 0.872340 (-827 -100);
PAINT GREEN (-827 -100);
DISPLAY INVISIBLE (-827 -100);
FORCEADD OFFPAGE..2
(225 2900);
FORCEPROP 2 LAST $XR0 350 
J 0
(414 2900);
DISPLAY 0.638298 (414 2900);
PAINT MONO (414 2900);
FORCEPROP 2 LAST CDS_LIB standard
J 0
(225 2900);
DISPLAY INVISIBLE (225 2900);
FORCEPROP 1 LAST OFFPAGE TRUE
J 0
(550 2775);
DISPLAY 0.872340 (550 2775);
DISPLAY INVISIBLE (550 2775);
FORCEPROP 1 LAST COMMENT_BODY TRUE
J 0
(180 2805);
DISPLAY 0.872340 (180 2805);
PAINT GREEN (180 2805);
DISPLAY INVISIBLE (180 2805);
FORCEPROP 2 LAST PATH I150
J 0
(425 2950);
DISPLAY 0.680851 (425 2950);
DISPLAY INVISIBLE (425 2950);
FORCEADD OFFPAGE..1
(1200 2875);
FORCEPROP 2 LAST $XR0 49 
J 0
(949 2875);
DISPLAY 0.638298 (949 2875);
PAINT MONO (949 2875);
FORCEPROP 2 LAST CDS_LIB standard
J 0
(1200 2875);
DISPLAY INVISIBLE (1200 2875);
FORCEPROP 1 LAST OFFPAGE TRUE
J 0
(1525 2750);
DISPLAY 0.872340 (1525 2750);
DISPLAY INVISIBLE (1525 2750);
FORCEPROP 1 LAST COMMENT_BODY TRUE
J 0
(1325 2775);
DISPLAY 0.872340 (1325 2775);
PAINT GREEN (1325 2775);
DISPLAY INVISIBLE (1325 2775);
FORCEPROP 2 LAST PATH I151
J 0
(1000 2925);
DISPLAY 0.680851 (1000 2925);
DISPLAY INVISIBLE (1000 2925);
FORCEADD OFFPAGE..1
(1200 2925);
FORCEPROP 2 LAST $XR0 49 
J 0
(949 2925);
DISPLAY 0.638298 (949 2925);
PAINT MONO (949 2925);
FORCEPROP 2 LAST CDS_LIB standard
J 0
(1200 2925);
DISPLAY INVISIBLE (1200 2925);
FORCEPROP 1 LAST OFFPAGE TRUE
J 0
(1525 2800);
DISPLAY 0.872340 (1525 2800);
DISPLAY INVISIBLE (1525 2800);
FORCEPROP 1 LAST COMMENT_BODY TRUE
J 0
(1325 2825);
DISPLAY 0.872340 (1325 2825);
PAINT GREEN (1325 2825);
DISPLAY INVISIBLE (1325 2825);
FORCEPROP 2 LAST PATH I152
J 0
(1000 2975);
DISPLAY 0.680851 (1000 2975);
DISPLAY INVISIBLE (1000 2975);
FORCEADD TAP..1
R 2
(2175 -25);
FORCEPROP 3 LASTPIN (2225 -25) SIG_NAME P3E_CPU1_P4_TX_DN<0>
J 0
(2235 -15);
DISPLAY 0.659574 (2235 -15);
PAINT MONO (2235 -15);
DISPLAY INVISIBLE (2235 -15);
FORCEPROP 1 LASTPIN (2225 -25) BN 0
J 2
(2237 -17);
DISPLAY 0.680851 (2237 -17);
PAINT MONO (2237 -17);
FORCEPROP 2 LAST CDS_LIB standard
J 0
(2175 -25);
DISPLAY INVISIBLE (2175 -25);
FORCEPROP 1 LAST BODY_TYPE PLUMBING
J 2
(2175 25);
DISPLAY 0.872340 (2175 25);
PAINT GREEN (2175 25);
DISPLAY INVISIBLE (2175 25);
FORCEPROP 1 LAST HDL_TAP TRUE
J 2
(1850 -150);
DISPLAY 0.872340 (1850 -150);
DISPLAY INVISIBLE (1850 -150);
FORCEPROP 1 LAST PATH I153
J 2
(2177 -25);
DISPLAY 0.872340 (2177 -25);
PAINT GREEN (2177 -25);
DISPLAY INVISIBLE (2177 -25);
FORCEADD TAP..1
R 2
(2425 25);
FORCEPROP 3 LASTPIN (2475 25) SIG_NAME P3E_CPU1_P4_TX_DP<0>
J 0
(2485 35);
DISPLAY 0.659574 (2485 35);
PAINT MONO (2485 35);
DISPLAY INVISIBLE (2485 35);
FORCEPROP 1 LASTPIN (2475 25) BN 0
J 2
(2487 33);
DISPLAY 0.680851 (2487 33);
PAINT MONO (2487 33);
FORCEPROP 2 LAST CDS_LIB standard
J 0
(2425 25);
DISPLAY INVISIBLE (2425 25);
FORCEPROP 1 LAST BODY_TYPE PLUMBING
J 2
(2425 75);
DISPLAY 0.872340 (2425 75);
PAINT GREEN (2425 75);
DISPLAY INVISIBLE (2425 75);
FORCEPROP 1 LAST HDL_TAP TRUE
J 2
(2100 -100);
DISPLAY 0.872340 (2100 -100);
DISPLAY INVISIBLE (2100 -100);
FORCEPROP 1 LAST PATH I154
J 2
(2427 25);
DISPLAY 0.872340 (2427 25);
PAINT GREEN (2427 25);
DISPLAY INVISIBLE (2427 25);
FORCEADD TAP..1
R 2
(2150 1450);
FORCEPROP 3 LASTPIN (2200 1450) SIG_NAME P5E_CPU1_G1_TX_DP<0>
J 0
(2210 1460);
DISPLAY 0.659574 (2210 1460);
PAINT MONO (2210 1460);
DISPLAY INVISIBLE (2210 1460);
FORCEPROP 1 LASTPIN (2200 1450) BN 0
J 2
(2212 1458);
DISPLAY 0.680851 (2212 1458);
PAINT GREEN (2212 1458);
FORCEPROP 2 LAST CDS_LIB standard
J 0
(2150 1450);
DISPLAY INVISIBLE (2150 1450);
FORCEPROP 1 LAST BODY_TYPE PLUMBING
J 2
(2150 1500);
DISPLAY 0.872340 (2150 1500);
PAINT GREEN (2150 1500);
DISPLAY INVISIBLE (2150 1500);
FORCEPROP 1 LAST HDL_TAP TRUE
J 2
(1825 1325);
DISPLAY 0.872340 (1825 1325);
DISPLAY INVISIBLE (1825 1325);
FORCEPROP 1 LAST PATH I155
J 2
(2152 1450);
DISPLAY 0.872340 (2152 1450);
PAINT GREEN (2152 1450);
DISPLAY INVISIBLE (2152 1450);
FORCEADD TAP..1
R 2
(2150 1650);
FORCEPROP 3 LASTPIN (2200 1650) SIG_NAME P5E_CPU1_G1_TX_DP<1>
J 0
(2210 1660);
DISPLAY 0.659574 (2210 1660);
PAINT MONO (2210 1660);
DISPLAY INVISIBLE (2210 1660);
FORCEPROP 1 LASTPIN (2200 1650) BN 1
J 2
(2212 1658);
DISPLAY 0.680851 (2212 1658);
PAINT GREEN (2212 1658);
FORCEPROP 2 LAST CDS_LIB standard
J 0
(2150 1650);
DISPLAY INVISIBLE (2150 1650);
FORCEPROP 1 LAST BODY_TYPE PLUMBING
J 2
(2150 1700);
DISPLAY 0.872340 (2150 1700);
PAINT GREEN (2150 1700);
DISPLAY INVISIBLE (2150 1700);
FORCEPROP 1 LAST HDL_TAP TRUE
J 2
(1825 1525);
DISPLAY 0.872340 (1825 1525);
DISPLAY INVISIBLE (1825 1525);
FORCEPROP 1 LAST PATH I156
J 2
(2152 1650);
DISPLAY 0.872340 (2152 1650);
PAINT GREEN (2152 1650);
DISPLAY INVISIBLE (2152 1650);
FORCEADD TAP..1
R 2
(2150 1850);
FORCEPROP 3 LASTPIN (2200 1850) SIG_NAME P5E_CPU1_G1_TX_DP<2>
J 0
(2210 1860);
DISPLAY 0.659574 (2210 1860);
PAINT MONO (2210 1860);
DISPLAY INVISIBLE (2210 1860);
FORCEPROP 1 LASTPIN (2200 1850) BN 2
J 2
(2212 1858);
DISPLAY 0.680851 (2212 1858);
PAINT GREEN (2212 1858);
FORCEPROP 2 LAST CDS_LIB standard
J 0
(2150 1850);
DISPLAY INVISIBLE (2150 1850);
FORCEPROP 1 LAST BODY_TYPE PLUMBING
J 2
(2150 1900);
DISPLAY 0.872340 (2150 1900);
PAINT GREEN (2150 1900);
DISPLAY INVISIBLE (2150 1900);
FORCEPROP 1 LAST HDL_TAP TRUE
J 2
(1825 1725);
DISPLAY 0.872340 (1825 1725);
DISPLAY INVISIBLE (1825 1725);
FORCEPROP 1 LAST PATH I157
J 2
(2152 1850);
DISPLAY 0.872340 (2152 1850);
PAINT GREEN (2152 1850);
DISPLAY INVISIBLE (2152 1850);
FORCEADD TAP..1
R 2
(2400 1500);
FORCEPROP 3 LASTPIN (2450 1500) SIG_NAME P5E_CPU1_G1_TX_DN<0>
J 0
(2460 1510);
DISPLAY 0.659574 (2460 1510);
PAINT MONO (2460 1510);
DISPLAY INVISIBLE (2460 1510);
FORCEPROP 1 LASTPIN (2450 1500) BN 0
J 2
(2462 1508);
DISPLAY 0.680851 (2462 1508);
PAINT GREEN (2462 1508);
FORCEPROP 2 LAST CDS_LIB standard
J 0
(2400 1500);
DISPLAY INVISIBLE (2400 1500);
FORCEPROP 1 LAST BODY_TYPE PLUMBING
J 2
(2400 1550);
DISPLAY 0.872340 (2400 1550);
PAINT GREEN (2400 1550);
DISPLAY INVISIBLE (2400 1550);
FORCEPROP 1 LAST HDL_TAP TRUE
J 2
(2075 1375);
DISPLAY 0.872340 (2075 1375);
DISPLAY INVISIBLE (2075 1375);
FORCEPROP 1 LAST PATH I158
J 2
(2402 1500);
DISPLAY 0.872340 (2402 1500);
PAINT GREEN (2402 1500);
DISPLAY INVISIBLE (2402 1500);
FORCEADD TAP..1
R 2
(2400 1700);
FORCEPROP 3 LASTPIN (2450 1700) SIG_NAME P5E_CPU1_G1_TX_DN<1>
J 0
(2460 1710);
DISPLAY 0.659574 (2460 1710);
PAINT MONO (2460 1710);
DISPLAY INVISIBLE (2460 1710);
FORCEPROP 1 LASTPIN (2450 1700) BN 1
J 2
(2462 1708);
DISPLAY 0.680851 (2462 1708);
PAINT GREEN (2462 1708);
FORCEPROP 2 LAST CDS_LIB standard
J 0
(2400 1700);
DISPLAY INVISIBLE (2400 1700);
FORCEPROP 1 LAST BODY_TYPE PLUMBING
J 2
(2400 1750);
DISPLAY 0.872340 (2400 1750);
PAINT GREEN (2400 1750);
DISPLAY INVISIBLE (2400 1750);
FORCEPROP 1 LAST HDL_TAP TRUE
J 2
(2075 1575);
DISPLAY 0.872340 (2075 1575);
DISPLAY INVISIBLE (2075 1575);
FORCEPROP 1 LAST PATH I159
J 2
(2402 1700);
DISPLAY 0.872340 (2402 1700);
PAINT GREEN (2402 1700);
DISPLAY INVISIBLE (2402 1700);
FORCEADD TAP..1
(-625 -550);
FORCEPROP 3 LASTPIN (-675 -550) SIG_NAME P3E_CPU0_P4_TX_C_DN<3>
J 0
(-665 -540);
DISPLAY 0.659574 (-665 -540);
PAINT MONO (-665 -540);
DISPLAY INVISIBLE (-665 -540);
FORCEPROP 1 LASTPIN (-675 -550) BN 3
J 0
(-687 -542);
DISPLAY 0.680851 (-687 -542);
PAINT MONO (-687 -542);
FORCEPROP 2 LAST CDS_LIB standard
J 0
(-625 -550);
DISPLAY INVISIBLE (-625 -550);
FORCEPROP 1 LAST BODY_TYPE PLUMBING
J 0
(-625 -500);
DISPLAY 0.872340 (-625 -500);
PAINT GREEN (-625 -500);
DISPLAY INVISIBLE (-625 -500);
FORCEPROP 1 LAST HDL_TAP TRUE
J 0
(-300 -675);
DISPLAY 0.872340 (-300 -675);
DISPLAY INVISIBLE (-300 -675);
FORCEPROP 1 LAST PATH I16
J 0
(-627 -550);
DISPLAY 0.872340 (-627 -550);
PAINT GREEN (-627 -550);
DISPLAY INVISIBLE (-627 -550);
FORCEADD TAP..1
R 2
(2400 1900);
FORCEPROP 3 LASTPIN (2450 1900) SIG_NAME P5E_CPU1_G1_TX_DN<2>
J 0
(2460 1910);
DISPLAY 0.659574 (2460 1910);
PAINT MONO (2460 1910);
DISPLAY INVISIBLE (2460 1910);
FORCEPROP 1 LASTPIN (2450 1900) BN 2
J 2
(2462 1908);
DISPLAY 0.680851 (2462 1908);
PAINT GREEN (2462 1908);
FORCEPROP 2 LAST CDS_LIB standard
J 0
(2400 1900);
DISPLAY INVISIBLE (2400 1900);
FORCEPROP 1 LAST BODY_TYPE PLUMBING
J 2
(2400 1950);
DISPLAY 0.872340 (2400 1950);
PAINT GREEN (2400 1950);
DISPLAY INVISIBLE (2400 1950);
FORCEPROP 1 LAST HDL_TAP TRUE
J 2
(2075 1775);
DISPLAY 0.872340 (2075 1775);
DISPLAY INVISIBLE (2075 1775);
FORCEPROP 1 LAST PATH I160
J 2
(2402 1900);
DISPLAY 0.872340 (2402 1900);
PAINT GREEN (2402 1900);
DISPLAY INVISIBLE (2402 1900);
FORCEADD Q_CAP_DIFFBUS..2
R 2
(3150 -25);
FORCEPROP 1 LAST LOCATION C9105
J 2
(3375 -25);
DISPLAY 0.723404 (3375 -25);
PAINT GREEN (3375 -25);
FORCEPROP 0 LAST $SEC 1
J 0
(3375 25);
DISPLAY 0.680851 (3375 25);
PAINT MONO (3375 25);
DISPLAY INVISIBLE (3375 25);
FORCEPROP 0 LAST CDS_SEC 1
J 0
(3375 25);
DISPLAY 0.680851 (3375 25);
DISPLAY INVISIBLE (3375 25);
FORCEPROP 0 LASTPIN (3225 -25) $PN 1
J 0
(3235 -15);
DISPLAY 0.680851 (3235 -15);
PAINT MONO (3235 -15);
FORCEPROP 0 LASTPIN (3075 -25) $PN 2
J 2
(3065 -15);
DISPLAY 0.680851 (3065 -15);
PAINT MONO (3065 -15);
FORCEPROP 2 LAST VALUE DIFF BUS_0.22UF
J 2
(3000 -25);
DISPLAY 0.553191 (3000 -25);
FORCEPROP 2 LAST TOLERANCE 20%
J 2
(3075 25);
DISPLAY 0.553191 (3075 25);
DISPLAY INVISIBLE (3075 25);
FORCEPROP 2 LAST PACK_TYPE C0201
J 2
(2975 25);
DISPLAY 0.553191 (2975 25);
DISPLAY INVISIBLE (2975 25);
FORCEPROP 1 LAST MATERIAL X6S
J 2
(3159 54);
DISPLAY 0.574468 (3159 54);
PAINT GREEN (3159 54);
DISPLAY INVISIBLE (3159 54);
FORCEPROP 2 LAST VOLTAGE 6.3V
J 2
(2800 25);
DISPLAY 0.553191 (2800 25);
DISPLAY INVISIBLE (2800 25);
FORCEPROP 1 LAST PIN_NAMES_ROTATE TRUE
J 2
(3150 -25);
DISPLAY 0.489362 (3150 -25);
PAINT GREEN (3150 -25);
DISPLAY INVISIBLE (3150 -25);
FORCEPROP 1 LAST CDS_LMAN_SYM_OUTLINE -25,50,25,-50
J 2
(3150 -25);
DISPLAY 0.468085 (3150 -25);
PAINT GREEN (3150 -25);
DISPLAY INVISIBLE (3150 -25);
FORCEPROP 2 LAST CDS_LIB pure_quanta
J 0
(3150 -25);
DISPLAY INVISIBLE (3150 -25);
FORCEPROP 1 LAST PART_NUMBER SP_CH4221MEE01
J 2
(3034 63);
DISPLAY 0.574468 (3034 63);
PAINT GREEN (3034 63);
DISPLAY INVISIBLE (3034 63);
FORCEPROP 1 LAST PATH I161
J 2
(3150 -25);
DISPLAY 0.723404 (3150 -25);
DISPLAY INVISIBLE (3150 -25);
FORCEADD Q_CAP_DIFFBUS..2
R 2
(3150 25);
FORCEPROP 1 LAST LOCATION C9104
J 2
(3375 25);
DISPLAY 0.723404 (3375 25);
PAINT GREEN (3375 25);
FORCEPROP 0 LAST $SEC 1
J 0
(3125 275);
DISPLAY 0.680851 (3125 275);
PAINT MONO (3125 275);
DISPLAY INVISIBLE (3125 275);
FORCEPROP 0 LAST CDS_SEC 1
J 0
(3125 275);
DISPLAY 0.680851 (3125 275);
DISPLAY INVISIBLE (3125 275);
FORCEPROP 0 LASTPIN (3225 25) $PN 1
J 0
(3235 35);
DISPLAY 0.680851 (3235 35);
PAINT MONO (3235 35);
FORCEPROP 0 LASTPIN (3075 25) $PN 2
J 2
(3065 35);
DISPLAY 0.680851 (3065 35);
PAINT MONO (3065 35);
FORCEPROP 2 LAST VALUE DIFF BUS_0.22UF
J 2
(3000 25);
DISPLAY 0.553191 (3000 25);
FORCEPROP 2 LAST VOLTAGE 6.3V
J 2
(3400 175);
DISPLAY 0.553191 (3400 175);
PAINT GREEN (3400 175);
FORCEPROP 1 LAST MATERIAL X6S
J 2
(3109 229);
DISPLAY 0.574468 (3109 229);
PAINT GREEN (3109 229);
FORCEPROP 2 LAST TOLERANCE 20%
J 2
(3250 175);
DISPLAY 0.553191 (3250 175);
PAINT GREEN (3250 175);
FORCEPROP 2 LAST PACK_TYPE C0201
J 2
(3150 175);
DISPLAY 0.553191 (3150 175);
PAINT GREEN (3150 175);
FORCEPROP 1 LAST PIN_NAMES_ROTATE TRUE
J 2
(3150 25);
DISPLAY 0.489362 (3150 25);
PAINT GREEN (3150 25);
DISPLAY INVISIBLE (3150 25);
FORCEPROP 1 LAST CDS_LMAN_SYM_OUTLINE -25,50,25,-50
J 2
(3150 25);
DISPLAY 0.468085 (3150 25);
PAINT GREEN (3150 25);
DISPLAY INVISIBLE (3150 25);
FORCEPROP 2 LAST CDS_LIB pure_quanta
J 0
(3150 25);
DISPLAY INVISIBLE (3150 25);
FORCEPROP 1 LAST PART_NUMBER SP_CH4221MEE01
J 2
(3409 113);
DISPLAY 0.574468 (3409 113);
PAINT GREEN (3409 113);
DISPLAY INVISIBLE (3409 113);
FORCEPROP 1 LAST PATH I162
J 2
(3150 25);
DISPLAY 0.723404 (3150 25);
DISPLAY INVISIBLE (3150 25);
FORCEADD TAP..1
(3700 25);
FORCEPROP 3 LASTPIN (3650 25) SIG_NAME P3E_CPU1_P4_TX_C_DP<0>
J 0
(3660 35);
DISPLAY 0.659574 (3660 35);
PAINT MONO (3660 35);
DISPLAY INVISIBLE (3660 35);
FORCEPROP 1 LASTPIN (3650 25) BN 0
J 0
(3638 33);
DISPLAY 0.680851 (3638 33);
PAINT MONO (3638 33);
FORCEPROP 2 LAST CDS_LIB standard
J 0
(3700 25);
DISPLAY INVISIBLE (3700 25);
FORCEPROP 1 LAST BODY_TYPE PLUMBING
J 0
(3700 75);
DISPLAY 0.872340 (3700 75);
PAINT GREEN (3700 75);
DISPLAY INVISIBLE (3700 75);
FORCEPROP 1 LAST HDL_TAP TRUE
J 0
(4025 -100);
DISPLAY 0.872340 (4025 -100);
DISPLAY INVISIBLE (4025 -100);
FORCEPROP 1 LAST PATH I163
J 0
(3698 25);
DISPLAY 0.872340 (3698 25);
PAINT GREEN (3698 25);
DISPLAY INVISIBLE (3698 25);
FORCEADD TAP..1
(3900 -25);
FORCEPROP 3 LASTPIN (3850 -25) SIG_NAME P3E_CPU1_P4_TX_C_DN<0>
J 0
(3860 -15);
DISPLAY 0.659574 (3860 -15);
PAINT MONO (3860 -15);
DISPLAY INVISIBLE (3860 -15);
FORCEPROP 1 LASTPIN (3850 -25) BN 0
J 0
(3838 -17);
DISPLAY 0.680851 (3838 -17);
PAINT MONO (3838 -17);
FORCEPROP 2 LAST CDS_LIB standard
J 0
(3900 -25);
DISPLAY INVISIBLE (3900 -25);
FORCEPROP 1 LAST BODY_TYPE PLUMBING
J 0
(3900 25);
DISPLAY 0.872340 (3900 25);
PAINT GREEN (3900 25);
DISPLAY INVISIBLE (3900 25);
FORCEPROP 1 LAST HDL_TAP TRUE
J 0
(4225 -150);
DISPLAY 0.872340 (4225 -150);
DISPLAY INVISIBLE (4225 -150);
FORCEPROP 1 LAST PATH I164
J 0
(3898 -25);
DISPLAY 0.872340 (3898 -25);
PAINT GREEN (3898 -25);
DISPLAY INVISIBLE (3898 -25);
FORCEADD Q_CAP_DIFFBUS..2
R 2
(3125 1450);
FORCEPROP 1 LAST LOCATION C709
J 2
(3359 1467);
DISPLAY 0.723404 (3359 1467);
PAINT GREEN (3359 1467);
FORCEPROP 2 LAST $SEC 1
J 2
(3300 1525);
DISPLAY 0.680851 (3300 1525);
PAINT MONO (3300 1525);
DISPLAY INVISIBLE (3300 1525);
FORCEPROP 2 LAST CDS_SEC 1
J 2
(3300 1525);
DISPLAY 0.680851 (3300 1525);
DISPLAY INVISIBLE (3300 1525);
FORCEPROP 2 LASTPIN (3200 1450) $PN 1
J 0
(3210 1460);
DISPLAY 0.808511 (3210 1460);
FORCEPROP 2 LASTPIN (3050 1450) $PN 2
J 2
(3040 1460);
DISPLAY 0.808511 (3040 1460);
FORCEPROP 2 LAST VALUE DIFF BUS_0.22UF
J 2
(2975 1450);
DISPLAY 0.553191 (2975 1450);
FORCEPROP 2 LAST TOLERANCE 20%
J 2
(3050 1500);
DISPLAY 0.553191 (3050 1500);
DISPLAY INVISIBLE (3050 1500);
FORCEPROP 2 LAST PACK_TYPE C0201
J 2
(2950 1500);
DISPLAY 0.553191 (2950 1500);
DISPLAY INVISIBLE (2950 1500);
FORCEPROP 1 LAST MATERIAL X6S
J 2
(3134 1529);
DISPLAY 0.574468 (3134 1529);
PAINT GREEN (3134 1529);
DISPLAY INVISIBLE (3134 1529);
FORCEPROP 2 LAST VOLTAGE 6.3V
J 2
(2775 1500);
DISPLAY 0.553191 (2775 1500);
DISPLAY INVISIBLE (2775 1500);
FORCEPROP 1 LAST CDS_LMAN_SYM_OUTLINE -25,50,25,-50
J 2
(3125 1450);
DISPLAY 0.468085 (3125 1450);
PAINT GREEN (3125 1450);
DISPLAY INVISIBLE (3125 1450);
FORCEPROP 2 LAST CDS_LIB pure_quanta
J 2
(3125 1450);
DISPLAY INVISIBLE (3125 1450);
FORCEPROP 1 LAST PIN_NAMES_ROTATE TRUE
J 2
(3125 1450);
DISPLAY 0.489362 (3125 1450);
PAINT GREEN (3125 1450);
DISPLAY INVISIBLE (3125 1450);
FORCEPROP 1 LAST PART_NUMBER SP_CH4221MEE01
J 2
(3009 1538);
DISPLAY 0.574468 (3009 1538);
PAINT GREEN (3009 1538);
DISPLAY INVISIBLE (3009 1538);
FORCEPROP 1 LAST LOCATION C709
J 0
(3375 1525);
DISPLAY 1.021277 (3375 1525);
DISPLAY INVISIBLE (3375 1525);
FORCEPROP 1 LAST PATH I165
J 2
(3125 1450);
DISPLAY 0.723404 (3125 1450);
DISPLAY INVISIBLE (3125 1450);
FORCEADD Q_CAP_DIFFBUS..2
R 2
(3125 1500);
FORCEPROP 1 LAST LOCATION C708
J 2
(3359 1517);
DISPLAY 0.723404 (3359 1517);
PAINT GREEN (3359 1517);
FORCEPROP 2 LAST $SEC 1
J 2
(3300 1575);
DISPLAY 0.680851 (3300 1575);
PAINT MONO (3300 1575);
DISPLAY INVISIBLE (3300 1575);
FORCEPROP 2 LAST CDS_SEC 1
J 2
(3300 1575);
DISPLAY 0.680851 (3300 1575);
DISPLAY INVISIBLE (3300 1575);
FORCEPROP 2 LASTPIN (3200 1500) $PN 1
J 0
(3210 1510);
DISPLAY 0.808511 (3210 1510);
FORCEPROP 2 LASTPIN (3050 1500) $PN 2
J 2
(3040 1510);
DISPLAY 0.808511 (3040 1510);
FORCEPROP 2 LAST VALUE DIFF BUS_0.22UF
J 2
(2975 1500);
DISPLAY 0.553191 (2975 1500);
FORCEPROP 2 LAST TOLERANCE 20%
J 2
(3050 1550);
DISPLAY 0.553191 (3050 1550);
DISPLAY INVISIBLE (3050 1550);
FORCEPROP 2 LAST PACK_TYPE C0201
J 2
(2950 1550);
DISPLAY 0.553191 (2950 1550);
DISPLAY INVISIBLE (2950 1550);
FORCEPROP 1 LAST MATERIAL X6S
J 2
(3134 1579);
DISPLAY 0.574468 (3134 1579);
PAINT GREEN (3134 1579);
DISPLAY INVISIBLE (3134 1579);
FORCEPROP 2 LAST VOLTAGE 6.3V
J 2
(2775 1550);
DISPLAY 0.553191 (2775 1550);
DISPLAY INVISIBLE (2775 1550);
FORCEPROP 1 LAST CDS_LMAN_SYM_OUTLINE -25,50,25,-50
J 2
(3125 1500);
DISPLAY 0.468085 (3125 1500);
PAINT GREEN (3125 1500);
DISPLAY INVISIBLE (3125 1500);
FORCEPROP 2 LAST CDS_LIB pure_quanta
J 2
(3125 1500);
DISPLAY INVISIBLE (3125 1500);
FORCEPROP 1 LAST PIN_NAMES_ROTATE TRUE
J 2
(3125 1500);
DISPLAY 0.489362 (3125 1500);
PAINT GREEN (3125 1500);
DISPLAY INVISIBLE (3125 1500);
FORCEPROP 1 LAST PART_NUMBER SP_CH4221MEE01
J 2
(3009 1588);
DISPLAY 0.574468 (3009 1588);
PAINT GREEN (3009 1588);
DISPLAY INVISIBLE (3009 1588);
FORCEPROP 1 LAST LOCATION C708
J 0
(3375 1575);
DISPLAY 1.021277 (3375 1575);
DISPLAY INVISIBLE (3375 1575);
FORCEPROP 1 LAST PATH I166
J 2
(3125 1500);
DISPLAY 0.723404 (3125 1500);
DISPLAY INVISIBLE (3125 1500);
FORCEADD Q_CAP_DIFFBUS..2
R 2
(3125 1700);
FORCEPROP 1 LAST LOCATION C706
J 2
(3359 1717);
DISPLAY 0.723404 (3359 1717);
PAINT GREEN (3359 1717);
FORCEPROP 2 LAST $SEC 1
J 2
(3300 1775);
DISPLAY 0.680851 (3300 1775);
PAINT MONO (3300 1775);
DISPLAY INVISIBLE (3300 1775);
FORCEPROP 2 LAST CDS_SEC 1
J 2
(3300 1775);
DISPLAY 0.680851 (3300 1775);
DISPLAY INVISIBLE (3300 1775);
FORCEPROP 2 LASTPIN (3200 1700) $PN 1
J 0
(3210 1710);
DISPLAY 0.808511 (3210 1710);
FORCEPROP 2 LASTPIN (3050 1700) $PN 2
J 2
(3040 1710);
DISPLAY 0.808511 (3040 1710);
FORCEPROP 2 LAST VALUE DIFF BUS_0.22UF
J 2
(2975 1700);
DISPLAY 0.553191 (2975 1700);
FORCEPROP 2 LAST TOLERANCE 20%
J 2
(3050 1750);
DISPLAY 0.553191 (3050 1750);
DISPLAY INVISIBLE (3050 1750);
FORCEPROP 2 LAST PACK_TYPE C0201
J 2
(2950 1750);
DISPLAY 0.553191 (2950 1750);
DISPLAY INVISIBLE (2950 1750);
FORCEPROP 1 LAST MATERIAL X6S
J 2
(3134 1779);
DISPLAY 0.574468 (3134 1779);
PAINT GREEN (3134 1779);
DISPLAY INVISIBLE (3134 1779);
FORCEPROP 2 LAST VOLTAGE 6.3V
J 2
(2775 1750);
DISPLAY 0.553191 (2775 1750);
DISPLAY INVISIBLE (2775 1750);
FORCEPROP 2 LAST CDS_LIB pure_quanta
J 2
(3125 1700);
DISPLAY INVISIBLE (3125 1700);
FORCEPROP 1 LAST CDS_LMAN_SYM_OUTLINE -25,50,25,-50
J 2
(3125 1700);
DISPLAY 0.468085 (3125 1700);
PAINT GREEN (3125 1700);
DISPLAY INVISIBLE (3125 1700);
FORCEPROP 1 LAST PIN_NAMES_ROTATE TRUE
J 2
(3125 1700);
DISPLAY 0.489362 (3125 1700);
PAINT GREEN (3125 1700);
DISPLAY INVISIBLE (3125 1700);
FORCEPROP 1 LAST PART_NUMBER SP_CH4221MEE01
J 2
(3009 1788);
DISPLAY 0.574468 (3009 1788);
PAINT GREEN (3009 1788);
DISPLAY INVISIBLE (3009 1788);
FORCEPROP 1 LAST LOCATION C706
J 0
(3375 1775);
DISPLAY 1.021277 (3375 1775);
DISPLAY INVISIBLE (3375 1775);
FORCEPROP 1 LAST PATH I167
J 2
(3125 1700);
DISPLAY 0.723404 (3125 1700);
DISPLAY INVISIBLE (3125 1700);
FORCEADD Q_CAP_DIFFBUS..2
R 2
(3125 1650);
FORCEPROP 1 LAST LOCATION C707
J 2
(3359 1667);
DISPLAY 0.723404 (3359 1667);
PAINT GREEN (3359 1667);
FORCEPROP 2 LAST $SEC 1
J 2
(3300 1725);
DISPLAY 0.680851 (3300 1725);
PAINT MONO (3300 1725);
DISPLAY INVISIBLE (3300 1725);
FORCEPROP 2 LAST CDS_SEC 1
J 2
(3300 1725);
DISPLAY 0.680851 (3300 1725);
DISPLAY INVISIBLE (3300 1725);
FORCEPROP 2 LASTPIN (3200 1650) $PN 1
J 0
(3210 1660);
DISPLAY 0.808511 (3210 1660);
FORCEPROP 2 LASTPIN (3050 1650) $PN 2
J 2
(3040 1660);
DISPLAY 0.808511 (3040 1660);
FORCEPROP 2 LAST VALUE DIFF BUS_0.22UF
J 2
(2975 1650);
DISPLAY 0.553191 (2975 1650);
FORCEPROP 2 LAST TOLERANCE 20%
J 2
(3050 1700);
DISPLAY 0.553191 (3050 1700);
DISPLAY INVISIBLE (3050 1700);
FORCEPROP 2 LAST PACK_TYPE C0201
J 2
(2950 1700);
DISPLAY 0.553191 (2950 1700);
DISPLAY INVISIBLE (2950 1700);
FORCEPROP 1 LAST MATERIAL X6S
J 2
(3134 1729);
DISPLAY 0.574468 (3134 1729);
PAINT GREEN (3134 1729);
DISPLAY INVISIBLE (3134 1729);
FORCEPROP 2 LAST VOLTAGE 6.3V
J 2
(2775 1700);
DISPLAY 0.553191 (2775 1700);
DISPLAY INVISIBLE (2775 1700);
FORCEPROP 1 LAST CDS_LMAN_SYM_OUTLINE -25,50,25,-50
J 2
(3125 1650);
DISPLAY 0.468085 (3125 1650);
PAINT GREEN (3125 1650);
DISPLAY INVISIBLE (3125 1650);
FORCEPROP 2 LAST CDS_LIB pure_quanta
J 2
(3125 1650);
DISPLAY INVISIBLE (3125 1650);
FORCEPROP 1 LAST PIN_NAMES_ROTATE TRUE
J 2
(3125 1650);
DISPLAY 0.489362 (3125 1650);
PAINT GREEN (3125 1650);
DISPLAY INVISIBLE (3125 1650);
FORCEPROP 1 LAST PART_NUMBER SP_CH4221MEE01
J 2
(3009 1738);
DISPLAY 0.574468 (3009 1738);
PAINT GREEN (3009 1738);
DISPLAY INVISIBLE (3009 1738);
FORCEPROP 1 LAST LOCATION C707
J 0
(3375 1725);
DISPLAY 1.021277 (3375 1725);
DISPLAY INVISIBLE (3375 1725);
FORCEPROP 1 LAST PATH I168
J 2
(3125 1650);
DISPLAY 0.723404 (3125 1650);
DISPLAY INVISIBLE (3125 1650);
FORCEADD Q_CAP_DIFFBUS..2
R 2
(3125 1850);
FORCEPROP 1 LAST LOCATION C705
J 2
(3359 1867);
DISPLAY 0.723404 (3359 1867);
PAINT GREEN (3359 1867);
FORCEPROP 2 LAST $SEC 1
J 2
(3300 1925);
DISPLAY 0.680851 (3300 1925);
PAINT MONO (3300 1925);
DISPLAY INVISIBLE (3300 1925);
FORCEPROP 2 LAST CDS_SEC 1
J 2
(3300 1925);
DISPLAY 0.680851 (3300 1925);
DISPLAY INVISIBLE (3300 1925);
FORCEPROP 2 LASTPIN (3200 1850) $PN 1
J 0
(3210 1860);
DISPLAY 0.808511 (3210 1860);
FORCEPROP 2 LASTPIN (3050 1850) $PN 2
J 2
(3040 1860);
DISPLAY 0.808511 (3040 1860);
FORCEPROP 2 LAST VALUE DIFF BUS_0.22UF
J 2
(2975 1850);
DISPLAY 0.553191 (2975 1850);
FORCEPROP 2 LAST TOLERANCE 20%
J 2
(3050 1900);
DISPLAY 0.553191 (3050 1900);
DISPLAY INVISIBLE (3050 1900);
FORCEPROP 2 LAST PACK_TYPE C0201
J 2
(2950 1900);
DISPLAY 0.553191 (2950 1900);
DISPLAY INVISIBLE (2950 1900);
FORCEPROP 1 LAST MATERIAL X6S
J 2
(3134 1929);
DISPLAY 0.574468 (3134 1929);
PAINT GREEN (3134 1929);
DISPLAY INVISIBLE (3134 1929);
FORCEPROP 2 LAST VOLTAGE 6.3V
J 2
(2775 1900);
DISPLAY 0.553191 (2775 1900);
DISPLAY INVISIBLE (2775 1900);
FORCEPROP 1 LAST CDS_LMAN_SYM_OUTLINE -25,50,25,-50
J 2
(3125 1850);
DISPLAY 0.468085 (3125 1850);
PAINT GREEN (3125 1850);
DISPLAY INVISIBLE (3125 1850);
FORCEPROP 2 LAST CDS_LIB pure_quanta
J 2
(3125 1850);
DISPLAY INVISIBLE (3125 1850);
FORCEPROP 1 LAST PIN_NAMES_ROTATE TRUE
J 2
(3125 1850);
DISPLAY 0.489362 (3125 1850);
PAINT GREEN (3125 1850);
DISPLAY INVISIBLE (3125 1850);
FORCEPROP 1 LAST PART_NUMBER SP_CH4221MEE01
J 2
(3009 1938);
DISPLAY 0.574468 (3009 1938);
PAINT GREEN (3009 1938);
DISPLAY INVISIBLE (3009 1938);
FORCEPROP 1 LAST LOCATION C705
J 0
(3375 1925);
DISPLAY 1.021277 (3375 1925);
DISPLAY INVISIBLE (3375 1925);
FORCEPROP 1 LAST PATH I169
J 2
(3125 1850);
DISPLAY 0.723404 (3125 1850);
DISPLAY INVISIBLE (3125 1850);
FORCEADD TAP..1
(-625 -350);
FORCEPROP 3 LASTPIN (-675 -350) SIG_NAME P3E_CPU0_P4_TX_C_DN<2>
J 0
(-665 -340);
DISPLAY 0.659574 (-665 -340);
PAINT MONO (-665 -340);
DISPLAY INVISIBLE (-665 -340);
FORCEPROP 1 LASTPIN (-675 -350) BN 2
J 0
(-687 -342);
DISPLAY 0.680851 (-687 -342);
PAINT MONO (-687 -342);
FORCEPROP 2 LAST CDS_LIB standard
J 0
(-625 -350);
DISPLAY INVISIBLE (-625 -350);
FORCEPROP 1 LAST BODY_TYPE PLUMBING
J 0
(-625 -300);
DISPLAY 0.872340 (-625 -300);
PAINT GREEN (-625 -300);
DISPLAY INVISIBLE (-625 -300);
FORCEPROP 1 LAST HDL_TAP TRUE
J 0
(-300 -475);
DISPLAY 0.872340 (-300 -475);
DISPLAY INVISIBLE (-300 -475);
FORCEPROP 1 LAST PATH I17
J 0
(-627 -350);
DISPLAY 0.872340 (-627 -350);
PAINT GREEN (-627 -350);
DISPLAY INVISIBLE (-627 -350);
FORCEADD Q_CAP_DIFFBUS..2
R 2
(3125 1900);
FORCEPROP 1 LAST LOCATION C704
J 2
(3359 1917);
DISPLAY 0.723404 (3359 1917);
PAINT GREEN (3359 1917);
FORCEPROP 2 LAST $SEC 1
J 2
(3300 1975);
DISPLAY 0.680851 (3300 1975);
PAINT MONO (3300 1975);
DISPLAY INVISIBLE (3300 1975);
FORCEPROP 2 LAST CDS_SEC 1
J 2
(3300 1975);
DISPLAY 0.680851 (3300 1975);
DISPLAY INVISIBLE (3300 1975);
FORCEPROP 2 LASTPIN (3200 1900) $PN 1
J 0
(3210 1910);
DISPLAY 0.808511 (3210 1910);
FORCEPROP 2 LASTPIN (3050 1900) $PN 2
J 2
(3040 1910);
DISPLAY 0.808511 (3040 1910);
FORCEPROP 2 LAST VALUE DIFF BUS_0.22UF
J 2
(2975 1900);
DISPLAY 0.553191 (2975 1900);
FORCEPROP 2 LAST TOLERANCE 20%
J 2
(3050 1950);
DISPLAY 0.553191 (3050 1950);
DISPLAY INVISIBLE (3050 1950);
FORCEPROP 2 LAST PACK_TYPE C0201
J 2
(2950 1950);
DISPLAY 0.553191 (2950 1950);
DISPLAY INVISIBLE (2950 1950);
FORCEPROP 1 LAST MATERIAL X6S
J 2
(3134 1979);
DISPLAY 0.574468 (3134 1979);
PAINT GREEN (3134 1979);
DISPLAY INVISIBLE (3134 1979);
FORCEPROP 2 LAST VOLTAGE 6.3V
J 2
(2775 1950);
DISPLAY 0.553191 (2775 1950);
DISPLAY INVISIBLE (2775 1950);
FORCEPROP 1 LAST CDS_LMAN_SYM_OUTLINE -25,50,25,-50
J 2
(3125 1900);
DISPLAY 0.468085 (3125 1900);
PAINT GREEN (3125 1900);
DISPLAY INVISIBLE (3125 1900);
FORCEPROP 2 LAST CDS_LIB pure_quanta
J 2
(3125 1900);
DISPLAY INVISIBLE (3125 1900);
FORCEPROP 1 LAST PIN_NAMES_ROTATE TRUE
J 2
(3125 1900);
DISPLAY 0.489362 (3125 1900);
PAINT GREEN (3125 1900);
DISPLAY INVISIBLE (3125 1900);
FORCEPROP 1 LAST PART_NUMBER SP_CH4221MEE01
J 2
(3009 1988);
DISPLAY 0.574468 (3009 1988);
PAINT GREEN (3009 1988);
DISPLAY INVISIBLE (3009 1988);
FORCEPROP 1 LAST LOCATION C704
J 0
(3375 1975);
DISPLAY 1.021277 (3375 1975);
DISPLAY INVISIBLE (3375 1975);
FORCEPROP 1 LAST PATH I170
J 2
(3125 1900);
DISPLAY 0.723404 (3125 1900);
DISPLAY INVISIBLE (3125 1900);
FORCEADD TAP..1
(3875 1450);
FORCEPROP 3 LASTPIN (3825 1450) SIG_NAME P5E_CPU1_G1_TX_C_DP<0>
J 0
(3835 1460);
DISPLAY 0.659574 (3835 1460);
PAINT MONO (3835 1460);
DISPLAY INVISIBLE (3835 1460);
FORCEPROP 1 LASTPIN (3825 1450) BN 0
J 0
(3813 1458);
DISPLAY 0.680851 (3813 1458);
PAINT GREEN (3813 1458);
FORCEPROP 2 LAST CDS_LIB standard
J 0
(3875 1450);
DISPLAY INVISIBLE (3875 1450);
FORCEPROP 1 LAST BODY_TYPE PLUMBING
J 0
(3875 1500);
DISPLAY 0.872340 (3875 1500);
PAINT GREEN (3875 1500);
DISPLAY INVISIBLE (3875 1500);
FORCEPROP 1 LAST HDL_TAP TRUE
J 0
(4200 1325);
DISPLAY 0.872340 (4200 1325);
DISPLAY INVISIBLE (4200 1325);
FORCEPROP 1 LAST PATH I171
J 0
(3873 1450);
DISPLAY 0.872340 (3873 1450);
PAINT GREEN (3873 1450);
DISPLAY INVISIBLE (3873 1450);
FORCEADD TAP..1
(3675 1500);
FORCEPROP 3 LASTPIN (3625 1500) SIG_NAME P5E_CPU1_G1_TX_C_DN<0>
J 0
(3635 1510);
DISPLAY 0.659574 (3635 1510);
PAINT MONO (3635 1510);
DISPLAY INVISIBLE (3635 1510);
FORCEPROP 1 LASTPIN (3625 1500) BN 0
J 0
(3613 1508);
DISPLAY 0.680851 (3613 1508);
PAINT GREEN (3613 1508);
FORCEPROP 2 LAST CDS_LIB standard
J 0
(3675 1500);
DISPLAY INVISIBLE (3675 1500);
FORCEPROP 1 LAST BODY_TYPE PLUMBING
J 0
(3675 1550);
DISPLAY 0.872340 (3675 1550);
PAINT GREEN (3675 1550);
DISPLAY INVISIBLE (3675 1550);
FORCEPROP 1 LAST HDL_TAP TRUE
J 0
(4000 1375);
DISPLAY 0.872340 (4000 1375);
DISPLAY INVISIBLE (4000 1375);
FORCEPROP 1 LAST PATH I172
J 0
(3673 1500);
DISPLAY 0.872340 (3673 1500);
PAINT GREEN (3673 1500);
DISPLAY INVISIBLE (3673 1500);
FORCEADD TAP..1
(3675 1700);
FORCEPROP 3 LASTPIN (3625 1700) SIG_NAME P5E_CPU1_G1_TX_C_DN<1>
J 0
(3635 1710);
DISPLAY 0.659574 (3635 1710);
PAINT MONO (3635 1710);
DISPLAY INVISIBLE (3635 1710);
FORCEPROP 1 LASTPIN (3625 1700) BN 1
J 0
(3613 1708);
DISPLAY 0.680851 (3613 1708);
PAINT GREEN (3613 1708);
FORCEPROP 2 LAST CDS_LIB standard
J 0
(3675 1700);
DISPLAY INVISIBLE (3675 1700);
FORCEPROP 1 LAST BODY_TYPE PLUMBING
J 0
(3675 1750);
DISPLAY 0.872340 (3675 1750);
PAINT GREEN (3675 1750);
DISPLAY INVISIBLE (3675 1750);
FORCEPROP 1 LAST HDL_TAP TRUE
J 0
(4000 1575);
DISPLAY 0.872340 (4000 1575);
DISPLAY INVISIBLE (4000 1575);
FORCEPROP 1 LAST PATH I173
J 0
(3673 1700);
DISPLAY 0.872340 (3673 1700);
PAINT GREEN (3673 1700);
DISPLAY INVISIBLE (3673 1700);
FORCEADD TAP..1
(3675 1900);
FORCEPROP 3 LASTPIN (3625 1900) SIG_NAME P5E_CPU1_G1_TX_C_DN<2>
J 0
(3635 1910);
DISPLAY 0.659574 (3635 1910);
PAINT MONO (3635 1910);
DISPLAY INVISIBLE (3635 1910);
FORCEPROP 1 LASTPIN (3625 1900) BN 2
J 0
(3613 1908);
DISPLAY 0.680851 (3613 1908);
PAINT GREEN (3613 1908);
FORCEPROP 2 LAST CDS_LIB standard
J 0
(3675 1900);
DISPLAY INVISIBLE (3675 1900);
FORCEPROP 1 LAST BODY_TYPE PLUMBING
J 0
(3675 1950);
DISPLAY 0.872340 (3675 1950);
PAINT GREEN (3675 1950);
DISPLAY INVISIBLE (3675 1950);
FORCEPROP 1 LAST HDL_TAP TRUE
J 0
(4000 1775);
DISPLAY 0.872340 (4000 1775);
DISPLAY INVISIBLE (4000 1775);
FORCEPROP 1 LAST PATH I174
J 0
(3673 1900);
DISPLAY 0.872340 (3673 1900);
PAINT GREEN (3673 1900);
DISPLAY INVISIBLE (3673 1900);
FORCEADD TAP..1
(3875 1650);
FORCEPROP 3 LASTPIN (3825 1650) SIG_NAME P5E_CPU1_G1_TX_C_DP<1>
J 0
(3835 1660);
DISPLAY 0.659574 (3835 1660);
PAINT MONO (3835 1660);
DISPLAY INVISIBLE (3835 1660);
FORCEPROP 1 LASTPIN (3825 1650) BN 1
J 0
(3813 1658);
DISPLAY 0.680851 (3813 1658);
PAINT GREEN (3813 1658);
FORCEPROP 2 LAST CDS_LIB standard
J 0
(3875 1650);
DISPLAY INVISIBLE (3875 1650);
FORCEPROP 1 LAST BODY_TYPE PLUMBING
J 0
(3875 1700);
DISPLAY 0.872340 (3875 1700);
PAINT GREEN (3875 1700);
DISPLAY INVISIBLE (3875 1700);
FORCEPROP 1 LAST HDL_TAP TRUE
J 0
(4200 1525);
DISPLAY 0.872340 (4200 1525);
DISPLAY INVISIBLE (4200 1525);
FORCEPROP 1 LAST PATH I175
J 0
(3873 1650);
DISPLAY 0.872340 (3873 1650);
PAINT GREEN (3873 1650);
DISPLAY INVISIBLE (3873 1650);
FORCEADD TAP..1
(3875 1850);
FORCEPROP 3 LASTPIN (3825 1850) SIG_NAME P5E_CPU1_G1_TX_C_DP<2>
J 0
(3835 1860);
DISPLAY 0.659574 (3835 1860);
PAINT MONO (3835 1860);
DISPLAY INVISIBLE (3835 1860);
FORCEPROP 1 LASTPIN (3825 1850) BN 2
J 0
(3813 1858);
DISPLAY 0.680851 (3813 1858);
PAINT GREEN (3813 1858);
FORCEPROP 2 LAST CDS_LIB standard
J 0
(3875 1850);
DISPLAY INVISIBLE (3875 1850);
FORCEPROP 1 LAST BODY_TYPE PLUMBING
J 0
(3875 1900);
DISPLAY 0.872340 (3875 1900);
PAINT GREEN (3875 1900);
DISPLAY INVISIBLE (3875 1900);
FORCEPROP 1 LAST HDL_TAP TRUE
J 0
(4200 1725);
DISPLAY 0.872340 (4200 1725);
DISPLAY INVISIBLE (4200 1725);
FORCEPROP 1 LAST PATH I176
J 0
(3873 1850);
DISPLAY 0.872340 (3873 1850);
PAINT GREEN (3873 1850);
DISPLAY INVISIBLE (3873 1850);
FORCEADD TAP..1
R 2
(2150 2050);
FORCEPROP 3 LASTPIN (2200 2050) SIG_NAME P5E_CPU1_G1_TX_DP<3>
J 0
(2210 2060);
DISPLAY 0.659574 (2210 2060);
PAINT MONO (2210 2060);
DISPLAY INVISIBLE (2210 2060);
FORCEPROP 1 LASTPIN (2200 2050) BN 3
J 2
(2212 2058);
DISPLAY 0.680851 (2212 2058);
PAINT GREEN (2212 2058);
FORCEPROP 2 LAST CDS_LIB standard
J 0
(2150 2050);
DISPLAY INVISIBLE (2150 2050);
FORCEPROP 1 LAST BODY_TYPE PLUMBING
J 2
(2150 2100);
DISPLAY 0.872340 (2150 2100);
PAINT GREEN (2150 2100);
DISPLAY INVISIBLE (2150 2100);
FORCEPROP 1 LAST HDL_TAP TRUE
J 2
(1825 1925);
DISPLAY 0.872340 (1825 1925);
DISPLAY INVISIBLE (1825 1925);
FORCEPROP 1 LAST PATH I177
J 2
(2152 2050);
DISPLAY 0.872340 (2152 2050);
PAINT GREEN (2152 2050);
DISPLAY INVISIBLE (2152 2050);
FORCEADD TAP..1
R 2
(2150 2450);
FORCEPROP 3 LASTPIN (2200 2450) SIG_NAME P5E_CPU1_G1_TX_DP<5>
J 0
(2210 2460);
DISPLAY 0.659574 (2210 2460);
PAINT MONO (2210 2460);
DISPLAY INVISIBLE (2210 2460);
FORCEPROP 1 LASTPIN (2200 2450) BN 5
J 2
(2212 2458);
DISPLAY 0.680851 (2212 2458);
PAINT GREEN (2212 2458);
FORCEPROP 2 LAST CDS_LIB standard
J 0
(2150 2450);
DISPLAY INVISIBLE (2150 2450);
FORCEPROP 1 LAST BODY_TYPE PLUMBING
J 2
(2150 2500);
DISPLAY 0.872340 (2150 2500);
PAINT GREEN (2150 2500);
DISPLAY INVISIBLE (2150 2500);
FORCEPROP 1 LAST HDL_TAP TRUE
J 2
(1825 2325);
DISPLAY 0.872340 (1825 2325);
DISPLAY INVISIBLE (1825 2325);
FORCEPROP 1 LAST PATH I178
J 2
(2152 2450);
DISPLAY 0.872340 (2152 2450);
PAINT GREEN (2152 2450);
DISPLAY INVISIBLE (2152 2450);
FORCEADD TAP..1
R 2
(2150 2250);
FORCEPROP 3 LASTPIN (2200 2250) SIG_NAME P5E_CPU1_G1_TX_DP<4>
J 0
(2210 2260);
DISPLAY 0.659574 (2210 2260);
PAINT MONO (2210 2260);
DISPLAY INVISIBLE (2210 2260);
FORCEPROP 1 LASTPIN (2200 2250) BN 4
J 2
(2212 2258);
DISPLAY 0.680851 (2212 2258);
PAINT GREEN (2212 2258);
FORCEPROP 2 LAST CDS_LIB standard
J 0
(2150 2250);
DISPLAY INVISIBLE (2150 2250);
FORCEPROP 1 LAST BODY_TYPE PLUMBING
J 2
(2150 2300);
DISPLAY 0.872340 (2150 2300);
PAINT GREEN (2150 2300);
DISPLAY INVISIBLE (2150 2300);
FORCEPROP 1 LAST HDL_TAP TRUE
J 2
(1825 2125);
DISPLAY 0.872340 (1825 2125);
DISPLAY INVISIBLE (1825 2125);
FORCEPROP 1 LAST PATH I179
J 2
(2152 2250);
DISPLAY 0.872340 (2152 2250);
PAINT GREEN (2152 2250);
DISPLAY INVISIBLE (2152 2250);
FORCEADD TAP..1
(-625 -150);
FORCEPROP 3 LASTPIN (-675 -150) SIG_NAME P3E_CPU0_P4_TX_C_DN<1>
J 0
(-665 -140);
DISPLAY 0.659574 (-665 -140);
PAINT MONO (-665 -140);
DISPLAY INVISIBLE (-665 -140);
FORCEPROP 1 LASTPIN (-675 -150) BN 1
J 0
(-687 -142);
DISPLAY 0.680851 (-687 -142);
PAINT MONO (-687 -142);
FORCEPROP 2 LAST CDS_LIB standard
J 0
(-625 -150);
DISPLAY INVISIBLE (-625 -150);
FORCEPROP 1 LAST BODY_TYPE PLUMBING
J 0
(-625 -100);
DISPLAY 0.872340 (-625 -100);
PAINT GREEN (-625 -100);
DISPLAY INVISIBLE (-625 -100);
FORCEPROP 1 LAST HDL_TAP TRUE
J 0
(-300 -275);
DISPLAY 0.872340 (-300 -275);
DISPLAY INVISIBLE (-300 -275);
FORCEPROP 1 LAST PATH I18
J 0
(-627 -150);
DISPLAY 0.872340 (-627 -150);
PAINT GREEN (-627 -150);
DISPLAY INVISIBLE (-627 -150);
FORCEADD TAP..1
R 2
(2400 2100);
FORCEPROP 3 LASTPIN (2450 2100) SIG_NAME P5E_CPU1_G1_TX_DN<3>
J 0
(2460 2110);
DISPLAY 0.659574 (2460 2110);
PAINT MONO (2460 2110);
DISPLAY INVISIBLE (2460 2110);
FORCEPROP 1 LASTPIN (2450 2100) BN 3
J 2
(2462 2108);
DISPLAY 0.680851 (2462 2108);
PAINT GREEN (2462 2108);
FORCEPROP 2 LAST CDS_LIB standard
J 0
(2400 2100);
DISPLAY INVISIBLE (2400 2100);
FORCEPROP 1 LAST BODY_TYPE PLUMBING
J 2
(2400 2150);
DISPLAY 0.872340 (2400 2150);
PAINT GREEN (2400 2150);
DISPLAY INVISIBLE (2400 2150);
FORCEPROP 1 LAST HDL_TAP TRUE
J 2
(2075 1975);
DISPLAY 0.872340 (2075 1975);
DISPLAY INVISIBLE (2075 1975);
FORCEPROP 1 LAST PATH I180
J 2
(2402 2100);
DISPLAY 0.872340 (2402 2100);
PAINT GREEN (2402 2100);
DISPLAY INVISIBLE (2402 2100);
FORCEADD TAP..1
R 2
(2400 2300);
FORCEPROP 3 LASTPIN (2450 2300) SIG_NAME P5E_CPU1_G1_TX_DN<4>
J 0
(2460 2310);
DISPLAY 0.659574 (2460 2310);
PAINT MONO (2460 2310);
DISPLAY INVISIBLE (2460 2310);
FORCEPROP 1 LASTPIN (2450 2300) BN 4
J 2
(2462 2308);
DISPLAY 0.680851 (2462 2308);
PAINT GREEN (2462 2308);
FORCEPROP 2 LAST CDS_LIB standard
J 0
(2400 2300);
DISPLAY INVISIBLE (2400 2300);
FORCEPROP 1 LAST BODY_TYPE PLUMBING
J 2
(2400 2350);
DISPLAY 0.872340 (2400 2350);
PAINT GREEN (2400 2350);
DISPLAY INVISIBLE (2400 2350);
FORCEPROP 1 LAST HDL_TAP TRUE
J 2
(2075 2175);
DISPLAY 0.872340 (2075 2175);
DISPLAY INVISIBLE (2075 2175);
FORCEPROP 1 LAST PATH I181
J 2
(2402 2300);
DISPLAY 0.872340 (2402 2300);
PAINT GREEN (2402 2300);
DISPLAY INVISIBLE (2402 2300);
FORCEADD TAP..1
R 2
(2150 2650);
FORCEPROP 3 LASTPIN (2200 2650) SIG_NAME P5E_CPU1_G1_TX_DP<6>
J 0
(2210 2660);
DISPLAY 0.659574 (2210 2660);
PAINT MONO (2210 2660);
DISPLAY INVISIBLE (2210 2660);
FORCEPROP 1 LASTPIN (2200 2650) BN 6
J 2
(2212 2658);
DISPLAY 0.680851 (2212 2658);
PAINT GREEN (2212 2658);
FORCEPROP 2 LAST CDS_LIB standard
J 0
(2150 2650);
DISPLAY INVISIBLE (2150 2650);
FORCEPROP 1 LAST BODY_TYPE PLUMBING
J 2
(2150 2700);
DISPLAY 0.872340 (2150 2700);
PAINT GREEN (2150 2700);
DISPLAY INVISIBLE (2150 2700);
FORCEPROP 1 LAST HDL_TAP TRUE
J 2
(1825 2525);
DISPLAY 0.872340 (1825 2525);
DISPLAY INVISIBLE (1825 2525);
FORCEPROP 1 LAST PATH I182
J 2
(2152 2650);
DISPLAY 0.872340 (2152 2650);
PAINT GREEN (2152 2650);
DISPLAY INVISIBLE (2152 2650);
FORCEADD TAP..1
R 2
(2150 2850);
FORCEPROP 3 LASTPIN (2200 2850) SIG_NAME P5E_CPU1_G1_TX_DP<7>
J 0
(2210 2860);
DISPLAY 0.659574 (2210 2860);
PAINT MONO (2210 2860);
DISPLAY INVISIBLE (2210 2860);
FORCEPROP 1 LASTPIN (2200 2850) BN 7
J 2
(2212 2858);
DISPLAY 0.680851 (2212 2858);
PAINT GREEN (2212 2858);
FORCEPROP 2 LAST CDS_LIB standard
J 0
(2150 2850);
DISPLAY INVISIBLE (2150 2850);
FORCEPROP 1 LAST BODY_TYPE PLUMBING
J 2
(2150 2900);
DISPLAY 0.872340 (2150 2900);
PAINT GREEN (2150 2900);
DISPLAY INVISIBLE (2150 2900);
FORCEPROP 1 LAST HDL_TAP TRUE
J 2
(1825 2725);
DISPLAY 0.872340 (1825 2725);
DISPLAY INVISIBLE (1825 2725);
FORCEPROP 1 LAST PATH I183
J 2
(2152 2850);
DISPLAY 0.872340 (2152 2850);
PAINT GREEN (2152 2850);
DISPLAY INVISIBLE (2152 2850);
FORCEADD TAP..1
R 2
(2400 2700);
FORCEPROP 3 LASTPIN (2450 2700) SIG_NAME P5E_CPU1_G1_TX_DN<6>
J 0
(2460 2710);
DISPLAY 0.659574 (2460 2710);
PAINT MONO (2460 2710);
DISPLAY INVISIBLE (2460 2710);
FORCEPROP 1 LASTPIN (2450 2700) BN 6
J 2
(2462 2708);
DISPLAY 0.680851 (2462 2708);
PAINT GREEN (2462 2708);
FORCEPROP 2 LAST CDS_LIB standard
J 0
(2400 2700);
DISPLAY INVISIBLE (2400 2700);
FORCEPROP 1 LAST BODY_TYPE PLUMBING
J 2
(2400 2750);
DISPLAY 0.872340 (2400 2750);
PAINT GREEN (2400 2750);
DISPLAY INVISIBLE (2400 2750);
FORCEPROP 1 LAST HDL_TAP TRUE
J 2
(2075 2575);
DISPLAY 0.872340 (2075 2575);
DISPLAY INVISIBLE (2075 2575);
FORCEPROP 1 LAST PATH I184
J 2
(2402 2700);
DISPLAY 0.872340 (2402 2700);
PAINT GREEN (2402 2700);
DISPLAY INVISIBLE (2402 2700);
FORCEADD TAP..1
R 2
(2400 2500);
FORCEPROP 3 LASTPIN (2450 2500) SIG_NAME P5E_CPU1_G1_TX_DN<5>
J 0
(2460 2510);
DISPLAY 0.659574 (2460 2510);
PAINT MONO (2460 2510);
DISPLAY INVISIBLE (2460 2510);
FORCEPROP 1 LASTPIN (2450 2500) BN 5
J 2
(2462 2508);
DISPLAY 0.680851 (2462 2508);
PAINT GREEN (2462 2508);
FORCEPROP 2 LAST CDS_LIB standard
J 0
(2400 2500);
DISPLAY INVISIBLE (2400 2500);
FORCEPROP 1 LAST BODY_TYPE PLUMBING
J 2
(2400 2550);
DISPLAY 0.872340 (2400 2550);
PAINT GREEN (2400 2550);
DISPLAY INVISIBLE (2400 2550);
FORCEPROP 1 LAST HDL_TAP TRUE
J 2
(2075 2375);
DISPLAY 0.872340 (2075 2375);
DISPLAY INVISIBLE (2075 2375);
FORCEPROP 1 LAST PATH I185
J 2
(2402 2500);
DISPLAY 0.872340 (2402 2500);
PAINT GREEN (2402 2500);
DISPLAY INVISIBLE (2402 2500);
FORCEADD TAP..1
R 2
(2400 2900);
FORCEPROP 3 LASTPIN (2450 2900) SIG_NAME P5E_CPU1_G1_TX_DN<7>
J 0
(2460 2910);
DISPLAY 0.659574 (2460 2910);
PAINT MONO (2460 2910);
DISPLAY INVISIBLE (2460 2910);
FORCEPROP 1 LASTPIN (2450 2900) BN 7
J 2
(2462 2908);
DISPLAY 0.680851 (2462 2908);
PAINT GREEN (2462 2908);
FORCEPROP 2 LAST CDS_LIB standard
J 0
(2400 2900);
DISPLAY INVISIBLE (2400 2900);
FORCEPROP 1 LAST BODY_TYPE PLUMBING
J 2
(2400 2950);
DISPLAY 0.872340 (2400 2950);
PAINT GREEN (2400 2950);
DISPLAY INVISIBLE (2400 2950);
FORCEPROP 1 LAST HDL_TAP TRUE
J 2
(2075 2775);
DISPLAY 0.872340 (2075 2775);
DISPLAY INVISIBLE (2075 2775);
FORCEPROP 1 LAST PATH I186
J 2
(2402 2900);
DISPLAY 0.872340 (2402 2900);
PAINT GREEN (2402 2900);
DISPLAY INVISIBLE (2402 2900);
FORCEADD TAP..1
R 2
(2150 3050);
FORCEPROP 3 LASTPIN (2200 3050) SIG_NAME P5E_CPU1_G1_TX_DP<8>
J 0
(2210 3060);
DISPLAY 0.659574 (2210 3060);
PAINT MONO (2210 3060);
DISPLAY INVISIBLE (2210 3060);
FORCEPROP 1 LASTPIN (2200 3050) BN 8
J 2
(2212 3058);
DISPLAY 0.680851 (2212 3058);
PAINT GREEN (2212 3058);
FORCEPROP 2 LAST CDS_LIB standard
J 0
(2150 3050);
DISPLAY INVISIBLE (2150 3050);
FORCEPROP 1 LAST BODY_TYPE PLUMBING
J 2
(2150 3100);
DISPLAY 0.872340 (2150 3100);
PAINT GREEN (2150 3100);
DISPLAY INVISIBLE (2150 3100);
FORCEPROP 1 LAST HDL_TAP TRUE
J 2
(1825 2925);
DISPLAY 0.872340 (1825 2925);
DISPLAY INVISIBLE (1825 2925);
FORCEPROP 1 LAST PATH I187
J 2
(2152 3050);
DISPLAY 0.872340 (2152 3050);
PAINT GREEN (2152 3050);
DISPLAY INVISIBLE (2152 3050);
FORCEADD TAP..1
R 2
(2150 3250);
FORCEPROP 3 LASTPIN (2200 3250) SIG_NAME P5E_CPU1_G1_TX_DP<9>
J 0
(2210 3260);
DISPLAY 0.659574 (2210 3260);
PAINT MONO (2210 3260);
DISPLAY INVISIBLE (2210 3260);
FORCEPROP 1 LASTPIN (2200 3250) BN 9
J 2
(2212 3258);
DISPLAY 0.680851 (2212 3258);
PAINT GREEN (2212 3258);
FORCEPROP 2 LAST CDS_LIB standard
J 0
(2150 3250);
DISPLAY INVISIBLE (2150 3250);
FORCEPROP 1 LAST BODY_TYPE PLUMBING
J 2
(2150 3300);
DISPLAY 0.872340 (2150 3300);
PAINT GREEN (2150 3300);
DISPLAY INVISIBLE (2150 3300);
FORCEPROP 1 LAST HDL_TAP TRUE
J 2
(1825 3125);
DISPLAY 0.872340 (1825 3125);
DISPLAY INVISIBLE (1825 3125);
FORCEPROP 1 LAST PATH I188
J 2
(2152 3250);
DISPLAY 0.872340 (2152 3250);
PAINT GREEN (2152 3250);
DISPLAY INVISIBLE (2152 3250);
FORCEADD TAP..1
R 2
(2150 3450);
FORCEPROP 3 LASTPIN (2200 3450) SIG_NAME P5E_CPU1_G1_TX_DP<10>
J 0
(2210 3460);
DISPLAY 0.659574 (2210 3460);
PAINT MONO (2210 3460);
DISPLAY INVISIBLE (2210 3460);
FORCEPROP 1 LASTPIN (2200 3450) BN 10
J 2
(2212 3458);
DISPLAY 0.680851 (2212 3458);
PAINT GREEN (2212 3458);
FORCEPROP 2 LAST CDS_LIB standard
J 0
(2150 3450);
DISPLAY INVISIBLE (2150 3450);
FORCEPROP 1 LAST BODY_TYPE PLUMBING
J 2
(2150 3500);
DISPLAY 0.872340 (2150 3500);
PAINT GREEN (2150 3500);
DISPLAY INVISIBLE (2150 3500);
FORCEPROP 1 LAST HDL_TAP TRUE
J 2
(1825 3325);
DISPLAY 0.872340 (1825 3325);
DISPLAY INVISIBLE (1825 3325);
FORCEPROP 1 LAST PATH I189
J 2
(2152 3450);
DISPLAY 0.872340 (2152 3450);
PAINT GREEN (2152 3450);
DISPLAY INVISIBLE (2152 3450);
FORCEADD OFFPAGE..1
(-3300 75);
FORCEPROP 2 LAST $XR0 26 
J 0
(-3551 75);
DISPLAY 0.638298 (-3551 75);
PAINT MONO (-3551 75);
FORCEPROP 2 LAST CDS_LIB standard
J 0
(-3300 75);
DISPLAY INVISIBLE (-3300 75);
FORCEPROP 1 LAST OFFPAGE TRUE
J 0
(-2975 -50);
DISPLAY 0.872340 (-2975 -50);
DISPLAY INVISIBLE (-2975 -50);
FORCEPROP 1 LAST COMMENT_BODY TRUE
J 0
(-3175 -25);
DISPLAY 0.872340 (-3175 -25);
PAINT GREEN (-3175 -25);
DISPLAY INVISIBLE (-3175 -25);
FORCEPROP 2 LAST PATH I19
J 0
(-3250 150);
DISPLAY 0.680851 (-3250 150);
DISPLAY INVISIBLE (-3250 150);
FORCEADD TAP..1
R 2
(2400 3100);
FORCEPROP 3 LASTPIN (2450 3100) SIG_NAME P5E_CPU1_G1_TX_DN<8>
J 0
(2460 3110);
DISPLAY 0.659574 (2460 3110);
PAINT MONO (2460 3110);
DISPLAY INVISIBLE (2460 3110);
FORCEPROP 1 LASTPIN (2450 3100) BN 8
J 2
(2462 3108);
DISPLAY 0.680851 (2462 3108);
PAINT GREEN (2462 3108);
FORCEPROP 2 LAST CDS_LIB standard
J 0
(2400 3100);
DISPLAY INVISIBLE (2400 3100);
FORCEPROP 1 LAST BODY_TYPE PLUMBING
J 2
(2400 3150);
DISPLAY 0.872340 (2400 3150);
PAINT GREEN (2400 3150);
DISPLAY INVISIBLE (2400 3150);
FORCEPROP 1 LAST HDL_TAP TRUE
J 2
(2075 2975);
DISPLAY 0.872340 (2075 2975);
DISPLAY INVISIBLE (2075 2975);
FORCEPROP 1 LAST PATH I190
J 2
(2402 3100);
DISPLAY 0.872340 (2402 3100);
PAINT GREEN (2402 3100);
DISPLAY INVISIBLE (2402 3100);
FORCEADD TAP..1
R 2
(2400 3300);
FORCEPROP 3 LASTPIN (2450 3300) SIG_NAME P5E_CPU1_G1_TX_DN<9>
J 0
(2460 3310);
DISPLAY 0.659574 (2460 3310);
PAINT MONO (2460 3310);
DISPLAY INVISIBLE (2460 3310);
FORCEPROP 1 LASTPIN (2450 3300) BN 9
J 2
(2462 3308);
DISPLAY 0.680851 (2462 3308);
PAINT GREEN (2462 3308);
FORCEPROP 2 LAST CDS_LIB standard
J 0
(2400 3300);
DISPLAY INVISIBLE (2400 3300);
FORCEPROP 1 LAST BODY_TYPE PLUMBING
J 2
(2400 3350);
DISPLAY 0.872340 (2400 3350);
PAINT GREEN (2400 3350);
DISPLAY INVISIBLE (2400 3350);
FORCEPROP 1 LAST HDL_TAP TRUE
J 2
(2075 3175);
DISPLAY 0.872340 (2075 3175);
DISPLAY INVISIBLE (2075 3175);
FORCEPROP 1 LAST PATH I191
J 2
(2402 3300);
DISPLAY 0.872340 (2402 3300);
PAINT GREEN (2402 3300);
DISPLAY INVISIBLE (2402 3300);
FORCEADD TAP..1
R 2
(2400 3500);
FORCEPROP 3 LASTPIN (2450 3500) SIG_NAME P5E_CPU1_G1_TX_DN<10>
J 0
(2460 3510);
DISPLAY 0.659574 (2460 3510);
PAINT MONO (2460 3510);
DISPLAY INVISIBLE (2460 3510);
FORCEPROP 1 LASTPIN (2450 3500) BN 10
J 2
(2462 3508);
DISPLAY 0.680851 (2462 3508);
PAINT GREEN (2462 3508);
FORCEPROP 2 LAST CDS_LIB standard
J 0
(2400 3500);
DISPLAY INVISIBLE (2400 3500);
FORCEPROP 1 LAST BODY_TYPE PLUMBING
J 2
(2400 3550);
DISPLAY 0.872340 (2400 3550);
PAINT GREEN (2400 3550);
DISPLAY INVISIBLE (2400 3550);
FORCEPROP 1 LAST HDL_TAP TRUE
J 2
(2075 3375);
DISPLAY 0.872340 (2075 3375);
DISPLAY INVISIBLE (2075 3375);
FORCEPROP 1 LAST PATH I192
J 2
(2402 3500);
DISPLAY 0.872340 (2402 3500);
PAINT GREEN (2402 3500);
DISPLAY INVISIBLE (2402 3500);
FORCEADD TAP..1
R 2
(2150 3650);
FORCEPROP 3 LASTPIN (2200 3650) SIG_NAME P5E_CPU1_G1_TX_DP<11>
J 0
(2210 3660);
DISPLAY 0.659574 (2210 3660);
PAINT MONO (2210 3660);
DISPLAY INVISIBLE (2210 3660);
FORCEPROP 1 LASTPIN (2200 3650) BN 11
J 2
(2212 3658);
DISPLAY 0.680851 (2212 3658);
PAINT GREEN (2212 3658);
FORCEPROP 2 LAST CDS_LIB standard
J 0
(2150 3650);
DISPLAY INVISIBLE (2150 3650);
FORCEPROP 1 LAST BODY_TYPE PLUMBING
J 2
(2150 3700);
DISPLAY 0.872340 (2150 3700);
PAINT GREEN (2150 3700);
DISPLAY INVISIBLE (2150 3700);
FORCEPROP 1 LAST HDL_TAP TRUE
J 2
(1825 3525);
DISPLAY 0.872340 (1825 3525);
DISPLAY INVISIBLE (1825 3525);
FORCEPROP 1 LAST PATH I193
J 2
(2152 3650);
DISPLAY 0.872340 (2152 3650);
PAINT GREEN (2152 3650);
DISPLAY INVISIBLE (2152 3650);
FORCEADD TAP..1
R 2
(2150 3850);
FORCEPROP 3 LASTPIN (2200 3850) SIG_NAME P5E_CPU1_G1_TX_DP<12>
J 0
(2210 3860);
DISPLAY 0.659574 (2210 3860);
PAINT MONO (2210 3860);
DISPLAY INVISIBLE (2210 3860);
FORCEPROP 1 LASTPIN (2200 3850) BN 12
J 2
(2212 3858);
DISPLAY 0.680851 (2212 3858);
PAINT GREEN (2212 3858);
FORCEPROP 2 LAST CDS_LIB standard
J 0
(2150 3850);
DISPLAY INVISIBLE (2150 3850);
FORCEPROP 1 LAST BODY_TYPE PLUMBING
J 2
(2150 3900);
DISPLAY 0.872340 (2150 3900);
PAINT GREEN (2150 3900);
DISPLAY INVISIBLE (2150 3900);
FORCEPROP 1 LAST HDL_TAP TRUE
J 2
(1825 3725);
DISPLAY 0.872340 (1825 3725);
DISPLAY INVISIBLE (1825 3725);
FORCEPROP 1 LAST PATH I194
J 2
(2152 3850);
DISPLAY 0.872340 (2152 3850);
PAINT GREEN (2152 3850);
DISPLAY INVISIBLE (2152 3850);
FORCEADD TAP..1
R 2
(2400 3700);
FORCEPROP 3 LASTPIN (2450 3700) SIG_NAME P5E_CPU1_G1_TX_DN<11>
J 0
(2460 3710);
DISPLAY 0.659574 (2460 3710);
PAINT MONO (2460 3710);
DISPLAY INVISIBLE (2460 3710);
FORCEPROP 1 LASTPIN (2450 3700) BN 11
J 2
(2462 3708);
DISPLAY 0.680851 (2462 3708);
PAINT GREEN (2462 3708);
FORCEPROP 2 LAST CDS_LIB standard
J 0
(2400 3700);
DISPLAY INVISIBLE (2400 3700);
FORCEPROP 1 LAST BODY_TYPE PLUMBING
J 2
(2400 3750);
DISPLAY 0.872340 (2400 3750);
PAINT GREEN (2400 3750);
DISPLAY INVISIBLE (2400 3750);
FORCEPROP 1 LAST HDL_TAP TRUE
J 2
(2075 3575);
DISPLAY 0.872340 (2075 3575);
DISPLAY INVISIBLE (2075 3575);
FORCEPROP 1 LAST PATH I195
J 2
(2402 3700);
DISPLAY 0.872340 (2402 3700);
PAINT GREEN (2402 3700);
DISPLAY INVISIBLE (2402 3700);
FORCEADD TAP..1
R 2
(2400 3900);
FORCEPROP 3 LASTPIN (2450 3900) SIG_NAME P5E_CPU1_G1_TX_DN<12>
J 0
(2460 3910);
DISPLAY 0.659574 (2460 3910);
PAINT MONO (2460 3910);
DISPLAY INVISIBLE (2460 3910);
FORCEPROP 1 LASTPIN (2450 3900) BN 12
J 2
(2462 3908);
DISPLAY 0.680851 (2462 3908);
PAINT GREEN (2462 3908);
FORCEPROP 2 LAST CDS_LIB standard
J 0
(2400 3900);
DISPLAY INVISIBLE (2400 3900);
FORCEPROP 1 LAST BODY_TYPE PLUMBING
J 2
(2400 3950);
DISPLAY 0.872340 (2400 3950);
PAINT GREEN (2400 3950);
DISPLAY INVISIBLE (2400 3950);
FORCEPROP 1 LAST HDL_TAP TRUE
J 2
(2075 3775);
DISPLAY 0.872340 (2075 3775);
DISPLAY INVISIBLE (2075 3775);
FORCEPROP 1 LAST PATH I196
J 2
(2402 3900);
DISPLAY 0.872340 (2402 3900);
PAINT GREEN (2402 3900);
DISPLAY INVISIBLE (2402 3900);
FORCEADD Q_CAP_DIFFBUS..2
R 2
(3125 2100);
FORCEPROP 1 LAST LOCATION C702
J 2
(3359 2117);
DISPLAY 0.723404 (3359 2117);
PAINT GREEN (3359 2117);
FORCEPROP 2 LAST $SEC 1
J 2
(3300 2175);
DISPLAY 0.680851 (3300 2175);
PAINT MONO (3300 2175);
DISPLAY INVISIBLE (3300 2175);
FORCEPROP 2 LAST CDS_SEC 1
J 2
(3300 2175);
DISPLAY 0.680851 (3300 2175);
DISPLAY INVISIBLE (3300 2175);
FORCEPROP 2 LASTPIN (3200 2100) $PN 1
J 0
(3210 2110);
DISPLAY 0.808511 (3210 2110);
FORCEPROP 2 LASTPIN (3050 2100) $PN 2
J 2
(3040 2110);
DISPLAY 0.808511 (3040 2110);
FORCEPROP 2 LAST VALUE DIFF BUS_0.22UF
J 2
(2975 2100);
DISPLAY 0.553191 (2975 2100);
FORCEPROP 2 LAST TOLERANCE 20%
J 2
(3050 2150);
DISPLAY 0.553191 (3050 2150);
DISPLAY INVISIBLE (3050 2150);
FORCEPROP 2 LAST PACK_TYPE C0201
J 2
(2950 2150);
DISPLAY 0.553191 (2950 2150);
DISPLAY INVISIBLE (2950 2150);
FORCEPROP 1 LAST MATERIAL X6S
J 2
(3134 2179);
DISPLAY 0.574468 (3134 2179);
PAINT GREEN (3134 2179);
DISPLAY INVISIBLE (3134 2179);
FORCEPROP 2 LAST VOLTAGE 6.3V
J 2
(2775 2150);
DISPLAY 0.553191 (2775 2150);
DISPLAY INVISIBLE (2775 2150);
FORCEPROP 2 LAST CDS_LIB pure_quanta
J 2
(3125 2100);
DISPLAY INVISIBLE (3125 2100);
FORCEPROP 1 LAST CDS_LMAN_SYM_OUTLINE -25,50,25,-50
J 2
(3125 2100);
DISPLAY 0.468085 (3125 2100);
PAINT GREEN (3125 2100);
DISPLAY INVISIBLE (3125 2100);
FORCEPROP 1 LAST PIN_NAMES_ROTATE TRUE
J 2
(3125 2100);
DISPLAY 0.489362 (3125 2100);
PAINT GREEN (3125 2100);
DISPLAY INVISIBLE (3125 2100);
FORCEPROP 1 LAST PART_NUMBER SP_CH4221MEE01
J 2
(3009 2188);
DISPLAY 0.574468 (3009 2188);
PAINT GREEN (3009 2188);
DISPLAY INVISIBLE (3009 2188);
FORCEPROP 1 LAST LOCATION C702
J 0
(3375 2175);
DISPLAY 1.021277 (3375 2175);
DISPLAY INVISIBLE (3375 2175);
FORCEPROP 1 LAST PATH I197
J 2
(3125 2100);
DISPLAY 0.723404 (3125 2100);
DISPLAY INVISIBLE (3125 2100);
FORCEADD Q_CAP_DIFFBUS..2
R 2
(3125 2050);
FORCEPROP 1 LAST LOCATION C703
J 2
(3359 2067);
DISPLAY 0.723404 (3359 2067);
PAINT GREEN (3359 2067);
FORCEPROP 2 LAST $SEC 1
J 2
(3300 2125);
DISPLAY 0.680851 (3300 2125);
PAINT MONO (3300 2125);
DISPLAY INVISIBLE (3300 2125);
FORCEPROP 2 LAST CDS_SEC 1
J 2
(3300 2125);
DISPLAY 0.680851 (3300 2125);
DISPLAY INVISIBLE (3300 2125);
FORCEPROP 2 LASTPIN (3200 2050) $PN 1
J 0
(3210 2060);
DISPLAY 0.808511 (3210 2060);
FORCEPROP 2 LASTPIN (3050 2050) $PN 2
J 2
(3040 2060);
DISPLAY 0.808511 (3040 2060);
FORCEPROP 2 LAST VALUE DIFF BUS_0.22UF
J 2
(2975 2050);
DISPLAY 0.553191 (2975 2050);
FORCEPROP 2 LAST TOLERANCE 20%
J 2
(3050 2100);
DISPLAY 0.553191 (3050 2100);
DISPLAY INVISIBLE (3050 2100);
FORCEPROP 2 LAST PACK_TYPE C0201
J 2
(2950 2100);
DISPLAY 0.553191 (2950 2100);
DISPLAY INVISIBLE (2950 2100);
FORCEPROP 1 LAST MATERIAL X6S
J 2
(3134 2129);
DISPLAY 0.574468 (3134 2129);
PAINT GREEN (3134 2129);
DISPLAY INVISIBLE (3134 2129);
FORCEPROP 2 LAST VOLTAGE 6.3V
J 2
(2775 2100);
DISPLAY 0.553191 (2775 2100);
DISPLAY INVISIBLE (2775 2100);
FORCEPROP 2 LAST CDS_LIB pure_quanta
J 2
(3125 2050);
DISPLAY INVISIBLE (3125 2050);
FORCEPROP 1 LAST CDS_LMAN_SYM_OUTLINE -25,50,25,-50
J 2
(3125 2050);
DISPLAY 0.468085 (3125 2050);
PAINT GREEN (3125 2050);
DISPLAY INVISIBLE (3125 2050);
FORCEPROP 1 LAST PIN_NAMES_ROTATE TRUE
J 2
(3125 2050);
DISPLAY 0.489362 (3125 2050);
PAINT GREEN (3125 2050);
DISPLAY INVISIBLE (3125 2050);
FORCEPROP 1 LAST PART_NUMBER SP_CH4221MEE01
J 2
(3009 2138);
DISPLAY 0.574468 (3009 2138);
PAINT GREEN (3009 2138);
DISPLAY INVISIBLE (3009 2138);
FORCEPROP 1 LAST LOCATION C703
J 0
(3375 2125);
DISPLAY 1.021277 (3375 2125);
DISPLAY INVISIBLE (3375 2125);
FORCEPROP 1 LAST PATH I198
J 2
(3125 2050);
DISPLAY 0.723404 (3125 2050);
DISPLAY INVISIBLE (3125 2050);
FORCEADD Q_CAP_DIFFBUS..2
R 2
(3125 2250);
FORCEPROP 1 LAST LOCATION C701
J 2
(3359 2267);
DISPLAY 0.723404 (3359 2267);
PAINT GREEN (3359 2267);
FORCEPROP 2 LAST $SEC 1
J 2
(3300 2325);
DISPLAY 0.680851 (3300 2325);
PAINT MONO (3300 2325);
DISPLAY INVISIBLE (3300 2325);
FORCEPROP 2 LAST CDS_SEC 1
J 2
(3300 2325);
DISPLAY 0.680851 (3300 2325);
DISPLAY INVISIBLE (3300 2325);
FORCEPROP 2 LASTPIN (3200 2250) $PN 1
J 0
(3210 2260);
DISPLAY 0.808511 (3210 2260);
FORCEPROP 2 LASTPIN (3050 2250) $PN 2
J 2
(3040 2260);
DISPLAY 0.808511 (3040 2260);
FORCEPROP 2 LAST VALUE DIFF BUS_0.22UF
J 2
(2975 2250);
DISPLAY 0.553191 (2975 2250);
FORCEPROP 2 LAST TOLERANCE 20%
J 2
(3050 2300);
DISPLAY 0.553191 (3050 2300);
DISPLAY INVISIBLE (3050 2300);
FORCEPROP 2 LAST PACK_TYPE C0201
J 2
(2950 2300);
DISPLAY 0.553191 (2950 2300);
DISPLAY INVISIBLE (2950 2300);
FORCEPROP 1 LAST MATERIAL X6S
J 2
(3134 2329);
DISPLAY 0.574468 (3134 2329);
PAINT GREEN (3134 2329);
DISPLAY INVISIBLE (3134 2329);
FORCEPROP 2 LAST VOLTAGE 6.3V
J 2
(2775 2300);
DISPLAY 0.553191 (2775 2300);
DISPLAY INVISIBLE (2775 2300);
FORCEPROP 1 LAST CDS_LMAN_SYM_OUTLINE -25,50,25,-50
J 2
(3125 2250);
DISPLAY 0.468085 (3125 2250);
PAINT GREEN (3125 2250);
DISPLAY INVISIBLE (3125 2250);
FORCEPROP 2 LAST CDS_LIB pure_quanta
J 2
(3125 2250);
DISPLAY INVISIBLE (3125 2250);
FORCEPROP 1 LAST PIN_NAMES_ROTATE TRUE
J 2
(3125 2250);
DISPLAY 0.489362 (3125 2250);
PAINT GREEN (3125 2250);
DISPLAY INVISIBLE (3125 2250);
FORCEPROP 1 LAST PART_NUMBER SP_CH4221MEE01
J 2
(3009 2338);
DISPLAY 0.574468 (3009 2338);
PAINT GREEN (3009 2338);
DISPLAY INVISIBLE (3009 2338);
FORCEPROP 1 LAST LOCATION C701
J 0
(3375 2325);
DISPLAY 1.021277 (3375 2325);
DISPLAY INVISIBLE (3375 2325);
FORCEPROP 1 LAST PATH I199
J 2
(3125 2250);
DISPLAY 0.723404 (3125 2250);
DISPLAY INVISIBLE (3125 2250);
FORCEADD TAP..1
R 2
(-2350 -150);
FORCEPROP 3 LASTPIN (-2300 -150) SIG_NAME P3E_CPU0_P4_TX_DN<1>
J 0
(-2290 -140);
DISPLAY 0.659574 (-2290 -140);
PAINT MONO (-2290 -140);
DISPLAY INVISIBLE (-2290 -140);
FORCEPROP 1 LASTPIN (-2300 -150) BN 1
J 2
(-2288 -142);
DISPLAY 0.680851 (-2288 -142);
PAINT MONO (-2288 -142);
FORCEPROP 2 LAST CDS_LIB standard
J 0
(-2350 -150);
DISPLAY INVISIBLE (-2350 -150);
FORCEPROP 1 LAST BODY_TYPE PLUMBING
J 2
(-2350 -100);
DISPLAY 0.872340 (-2350 -100);
PAINT GREEN (-2350 -100);
DISPLAY INVISIBLE (-2350 -100);
FORCEPROP 1 LAST HDL_TAP TRUE
J 2
(-2675 -275);
DISPLAY 0.872340 (-2675 -275);
DISPLAY INVISIBLE (-2675 -275);
FORCEPROP 1 LAST PATH I2
J 2
(-2348 -150);
DISPLAY 0.872340 (-2348 -150);
PAINT GREEN (-2348 -150);
DISPLAY INVISIBLE (-2348 -150);
FORCEADD OFFPAGE..1
(-3300 125);
FORCEPROP 2 LAST $XR0 26 
J 0
(-3551 125);
DISPLAY 0.638298 (-3551 125);
PAINT MONO (-3551 125);
FORCEPROP 2 LAST CDS_LIB standard
J 0
(-3300 125);
DISPLAY INVISIBLE (-3300 125);
FORCEPROP 1 LAST OFFPAGE TRUE
J 0
(-2975 0);
DISPLAY 0.872340 (-2975 0);
DISPLAY INVISIBLE (-2975 0);
FORCEPROP 1 LAST COMMENT_BODY TRUE
J 0
(-3175 25);
DISPLAY 0.872340 (-3175 25);
PAINT GREEN (-3175 25);
DISPLAY INVISIBLE (-3175 25);
FORCEPROP 2 LAST PATH I20
J 0
(-3250 200);
DISPLAY 0.680851 (-3250 200);
DISPLAY INVISIBLE (-3250 200);
FORCEADD Q_CAP_DIFFBUS..2
R 2
(3125 2300);
FORCEPROP 1 LAST LOCATION C700
J 2
(3359 2317);
DISPLAY 0.723404 (3359 2317);
PAINT GREEN (3359 2317);
FORCEPROP 2 LAST $SEC 1
J 2
(3300 2375);
DISPLAY 0.680851 (3300 2375);
PAINT MONO (3300 2375);
DISPLAY INVISIBLE (3300 2375);
FORCEPROP 2 LAST CDS_SEC 1
J 2
(3300 2375);
DISPLAY 0.680851 (3300 2375);
DISPLAY INVISIBLE (3300 2375);
FORCEPROP 2 LASTPIN (3200 2300) $PN 1
J 0
(3210 2310);
DISPLAY 0.808511 (3210 2310);
FORCEPROP 2 LASTPIN (3050 2300) $PN 2
J 2
(3040 2310);
DISPLAY 0.808511 (3040 2310);
FORCEPROP 2 LAST VALUE DIFF BUS_0.22UF
J 2
(2975 2300);
DISPLAY 0.553191 (2975 2300);
FORCEPROP 2 LAST TOLERANCE 20%
J 2
(3050 2350);
DISPLAY 0.553191 (3050 2350);
DISPLAY INVISIBLE (3050 2350);
FORCEPROP 2 LAST PACK_TYPE C0201
J 2
(2950 2350);
DISPLAY 0.553191 (2950 2350);
DISPLAY INVISIBLE (2950 2350);
FORCEPROP 1 LAST MATERIAL X6S
J 2
(3134 2379);
DISPLAY 0.574468 (3134 2379);
PAINT GREEN (3134 2379);
DISPLAY INVISIBLE (3134 2379);
FORCEPROP 2 LAST VOLTAGE 6.3V
J 2
(2775 2350);
DISPLAY 0.553191 (2775 2350);
DISPLAY INVISIBLE (2775 2350);
FORCEPROP 1 LAST CDS_LMAN_SYM_OUTLINE -25,50,25,-50
J 2
(3125 2300);
DISPLAY 0.468085 (3125 2300);
PAINT GREEN (3125 2300);
DISPLAY INVISIBLE (3125 2300);
FORCEPROP 2 LAST CDS_LIB pure_quanta
J 2
(3125 2300);
DISPLAY INVISIBLE (3125 2300);
FORCEPROP 1 LAST PIN_NAMES_ROTATE TRUE
J 2
(3125 2300);
DISPLAY 0.489362 (3125 2300);
PAINT GREEN (3125 2300);
DISPLAY INVISIBLE (3125 2300);
FORCEPROP 1 LAST PART_NUMBER SP_CH4221MEE01
J 2
(3009 2388);
DISPLAY 0.574468 (3009 2388);
PAINT GREEN (3009 2388);
DISPLAY INVISIBLE (3009 2388);
FORCEPROP 1 LAST LOCATION C700
J 0
(3375 2375);
DISPLAY 1.021277 (3375 2375);
DISPLAY INVISIBLE (3375 2375);
FORCEPROP 1 LAST PATH I200
J 2
(3125 2300);
DISPLAY 0.723404 (3125 2300);
DISPLAY INVISIBLE (3125 2300);
FORCEADD Q_CAP_DIFFBUS..2
R 2
(3125 2500);
FORCEPROP 1 LAST LOCATION C698
J 2
(3359 2517);
DISPLAY 0.723404 (3359 2517);
PAINT GREEN (3359 2517);
FORCEPROP 2 LAST $SEC 1
J 2
(3300 2575);
DISPLAY 0.680851 (3300 2575);
PAINT MONO (3300 2575);
DISPLAY INVISIBLE (3300 2575);
FORCEPROP 2 LAST CDS_SEC 1
J 2
(3300 2575);
DISPLAY 0.680851 (3300 2575);
DISPLAY INVISIBLE (3300 2575);
FORCEPROP 2 LASTPIN (3200 2500) $PN 1
J 0
(3210 2510);
DISPLAY 0.808511 (3210 2510);
FORCEPROP 2 LASTPIN (3050 2500) $PN 2
J 2
(3040 2510);
DISPLAY 0.808511 (3040 2510);
FORCEPROP 2 LAST VALUE DIFF BUS_0.22UF
J 2
(2975 2500);
DISPLAY 0.553191 (2975 2500);
FORCEPROP 2 LAST TOLERANCE 20%
J 2
(3050 2550);
DISPLAY 0.553191 (3050 2550);
DISPLAY INVISIBLE (3050 2550);
FORCEPROP 2 LAST PACK_TYPE C0201
J 2
(2950 2550);
DISPLAY 0.553191 (2950 2550);
DISPLAY INVISIBLE (2950 2550);
FORCEPROP 1 LAST MATERIAL X6S
J 2
(3134 2579);
DISPLAY 0.574468 (3134 2579);
PAINT GREEN (3134 2579);
DISPLAY INVISIBLE (3134 2579);
FORCEPROP 2 LAST VOLTAGE 6.3V
J 2
(2775 2550);
DISPLAY 0.553191 (2775 2550);
DISPLAY INVISIBLE (2775 2550);
FORCEPROP 1 LAST CDS_LMAN_SYM_OUTLINE -25,50,25,-50
J 2
(3125 2500);
DISPLAY 0.468085 (3125 2500);
PAINT GREEN (3125 2500);
DISPLAY INVISIBLE (3125 2500);
FORCEPROP 2 LAST CDS_LIB pure_quanta
J 2
(3125 2500);
DISPLAY INVISIBLE (3125 2500);
FORCEPROP 1 LAST PIN_NAMES_ROTATE TRUE
J 2
(3125 2500);
DISPLAY 0.489362 (3125 2500);
PAINT GREEN (3125 2500);
DISPLAY INVISIBLE (3125 2500);
FORCEPROP 1 LAST PART_NUMBER SP_CH4221MEE01
J 2
(3009 2588);
DISPLAY 0.574468 (3009 2588);
PAINT GREEN (3009 2588);
DISPLAY INVISIBLE (3009 2588);
FORCEPROP 1 LAST LOCATION C698
J 0
(3375 2575);
DISPLAY 1.021277 (3375 2575);
DISPLAY INVISIBLE (3375 2575);
FORCEPROP 1 LAST PATH I201
J 2
(3125 2500);
DISPLAY 0.723404 (3125 2500);
DISPLAY INVISIBLE (3125 2500);
FORCEADD Q_CAP_DIFFBUS..2
R 2
(3125 2450);
FORCEPROP 1 LAST LOCATION C699
J 2
(3359 2467);
DISPLAY 0.723404 (3359 2467);
PAINT GREEN (3359 2467);
FORCEPROP 2 LAST $SEC 1
J 2
(3300 2525);
DISPLAY 0.680851 (3300 2525);
PAINT MONO (3300 2525);
DISPLAY INVISIBLE (3300 2525);
FORCEPROP 2 LAST CDS_SEC 1
J 2
(3300 2525);
DISPLAY 0.680851 (3300 2525);
DISPLAY INVISIBLE (3300 2525);
FORCEPROP 2 LASTPIN (3200 2450) $PN 1
J 0
(3210 2460);
DISPLAY 0.808511 (3210 2460);
FORCEPROP 2 LASTPIN (3050 2450) $PN 2
J 2
(3040 2460);
DISPLAY 0.808511 (3040 2460);
FORCEPROP 2 LAST VALUE DIFF BUS_0.22UF
J 2
(2975 2450);
DISPLAY 0.553191 (2975 2450);
FORCEPROP 2 LAST TOLERANCE 20%
J 2
(3050 2500);
DISPLAY 0.553191 (3050 2500);
DISPLAY INVISIBLE (3050 2500);
FORCEPROP 2 LAST PACK_TYPE C0201
J 2
(2950 2500);
DISPLAY 0.553191 (2950 2500);
DISPLAY INVISIBLE (2950 2500);
FORCEPROP 1 LAST MATERIAL X6S
J 2
(3134 2529);
DISPLAY 0.574468 (3134 2529);
PAINT GREEN (3134 2529);
DISPLAY INVISIBLE (3134 2529);
FORCEPROP 2 LAST VOLTAGE 6.3V
J 2
(2775 2500);
DISPLAY 0.553191 (2775 2500);
DISPLAY INVISIBLE (2775 2500);
FORCEPROP 1 LAST CDS_LMAN_SYM_OUTLINE -25,50,25,-50
J 2
(3125 2450);
DISPLAY 0.468085 (3125 2450);
PAINT GREEN (3125 2450);
DISPLAY INVISIBLE (3125 2450);
FORCEPROP 2 LAST CDS_LIB pure_quanta
J 2
(3125 2450);
DISPLAY INVISIBLE (3125 2450);
FORCEPROP 1 LAST PIN_NAMES_ROTATE TRUE
J 2
(3125 2450);
DISPLAY 0.489362 (3125 2450);
PAINT GREEN (3125 2450);
DISPLAY INVISIBLE (3125 2450);
FORCEPROP 1 LAST PART_NUMBER SP_CH4221MEE01
J 2
(3009 2538);
DISPLAY 0.574468 (3009 2538);
PAINT GREEN (3009 2538);
DISPLAY INVISIBLE (3009 2538);
FORCEPROP 1 LAST LOCATION C699
J 0
(3375 2525);
DISPLAY 1.021277 (3375 2525);
DISPLAY INVISIBLE (3375 2525);
FORCEPROP 1 LAST PATH I202
J 2
(3125 2450);
DISPLAY 0.723404 (3125 2450);
DISPLAY INVISIBLE (3125 2450);
FORCEADD Q_CAP_DIFFBUS..2
R 2
(3125 2650);
FORCEPROP 1 LAST LOCATION C697
J 2
(3359 2667);
DISPLAY 0.723404 (3359 2667);
PAINT GREEN (3359 2667);
FORCEPROP 2 LAST $SEC 1
J 2
(3300 2725);
DISPLAY 0.680851 (3300 2725);
PAINT MONO (3300 2725);
DISPLAY INVISIBLE (3300 2725);
FORCEPROP 2 LAST CDS_SEC 1
J 2
(3300 2725);
DISPLAY 0.680851 (3300 2725);
DISPLAY INVISIBLE (3300 2725);
FORCEPROP 2 LASTPIN (3200 2650) $PN 1
J 0
(3210 2660);
DISPLAY 0.808511 (3210 2660);
FORCEPROP 2 LASTPIN (3050 2650) $PN 2
J 2
(3040 2660);
DISPLAY 0.808511 (3040 2660);
FORCEPROP 2 LAST VALUE DIFF BUS_0.22UF
J 2
(2975 2650);
DISPLAY 0.553191 (2975 2650);
FORCEPROP 2 LAST TOLERANCE 20%
J 2
(3050 2700);
DISPLAY 0.553191 (3050 2700);
DISPLAY INVISIBLE (3050 2700);
FORCEPROP 2 LAST PACK_TYPE C0201
J 2
(2950 2700);
DISPLAY 0.553191 (2950 2700);
DISPLAY INVISIBLE (2950 2700);
FORCEPROP 1 LAST MATERIAL X6S
J 2
(3134 2729);
DISPLAY 0.574468 (3134 2729);
PAINT GREEN (3134 2729);
DISPLAY INVISIBLE (3134 2729);
FORCEPROP 2 LAST VOLTAGE 6.3V
J 2
(2775 2700);
DISPLAY 0.553191 (2775 2700);
DISPLAY INVISIBLE (2775 2700);
FORCEPROP 1 LAST CDS_LMAN_SYM_OUTLINE -25,50,25,-50
J 2
(3125 2650);
DISPLAY 0.468085 (3125 2650);
PAINT GREEN (3125 2650);
DISPLAY INVISIBLE (3125 2650);
FORCEPROP 2 LAST CDS_LIB pure_quanta
J 2
(3125 2650);
DISPLAY INVISIBLE (3125 2650);
FORCEPROP 1 LAST PIN_NAMES_ROTATE TRUE
J 2
(3125 2650);
DISPLAY 0.489362 (3125 2650);
PAINT GREEN (3125 2650);
DISPLAY INVISIBLE (3125 2650);
FORCEPROP 1 LAST PART_NUMBER SP_CH4221MEE01
J 2
(3009 2738);
DISPLAY 0.574468 (3009 2738);
PAINT GREEN (3009 2738);
DISPLAY INVISIBLE (3009 2738);
FORCEPROP 1 LAST LOCATION C697
J 0
(3375 2725);
DISPLAY 1.021277 (3375 2725);
DISPLAY INVISIBLE (3375 2725);
FORCEPROP 1 LAST PATH I203
J 2
(3125 2650);
DISPLAY 0.723404 (3125 2650);
DISPLAY INVISIBLE (3125 2650);
FORCEADD Q_CAP_DIFFBUS..2
R 2
(3125 2700);
FORCEPROP 1 LAST LOCATION C696
J 2
(3359 2717);
DISPLAY 0.723404 (3359 2717);
PAINT GREEN (3359 2717);
FORCEPROP 2 LAST $SEC 1
J 2
(3300 2775);
DISPLAY 0.680851 (3300 2775);
PAINT MONO (3300 2775);
DISPLAY INVISIBLE (3300 2775);
FORCEPROP 2 LAST CDS_SEC 1
J 2
(3300 2775);
DISPLAY 0.680851 (3300 2775);
DISPLAY INVISIBLE (3300 2775);
FORCEPROP 2 LASTPIN (3200 2700) $PN 1
J 0
(3210 2710);
DISPLAY 0.808511 (3210 2710);
FORCEPROP 2 LASTPIN (3050 2700) $PN 2
J 2
(3040 2710);
DISPLAY 0.808511 (3040 2710);
FORCEPROP 2 LAST VALUE DIFF BUS_0.22UF
J 2
(2975 2700);
DISPLAY 0.553191 (2975 2700);
FORCEPROP 2 LAST TOLERANCE 20%
J 2
(3050 2750);
DISPLAY 0.553191 (3050 2750);
DISPLAY INVISIBLE (3050 2750);
FORCEPROP 2 LAST PACK_TYPE C0201
J 2
(2950 2750);
DISPLAY 0.553191 (2950 2750);
DISPLAY INVISIBLE (2950 2750);
FORCEPROP 1 LAST MATERIAL X6S
J 2
(3134 2779);
DISPLAY 0.574468 (3134 2779);
PAINT GREEN (3134 2779);
DISPLAY INVISIBLE (3134 2779);
FORCEPROP 2 LAST VOLTAGE 6.3V
J 2
(2775 2750);
DISPLAY 0.553191 (2775 2750);
DISPLAY INVISIBLE (2775 2750);
FORCEPROP 1 LAST CDS_LMAN_SYM_OUTLINE -25,50,25,-50
J 2
(3125 2700);
DISPLAY 0.468085 (3125 2700);
PAINT GREEN (3125 2700);
DISPLAY INVISIBLE (3125 2700);
FORCEPROP 2 LAST CDS_LIB pure_quanta
J 2
(3125 2700);
DISPLAY INVISIBLE (3125 2700);
FORCEPROP 1 LAST PIN_NAMES_ROTATE TRUE
J 2
(3125 2700);
DISPLAY 0.489362 (3125 2700);
PAINT GREEN (3125 2700);
DISPLAY INVISIBLE (3125 2700);
FORCEPROP 1 LAST PART_NUMBER SP_CH4221MEE01
J 2
(3009 2788);
DISPLAY 0.574468 (3009 2788);
PAINT GREEN (3009 2788);
DISPLAY INVISIBLE (3009 2788);
FORCEPROP 1 LAST LOCATION C696
J 0
(3375 2775);
DISPLAY 1.021277 (3375 2775);
DISPLAY INVISIBLE (3375 2775);
FORCEPROP 1 LAST PATH I204
J 2
(3125 2700);
DISPLAY 0.723404 (3125 2700);
DISPLAY INVISIBLE (3125 2700);
FORCEADD Q_CAP_DIFFBUS..2
R 2
(3125 2850);
FORCEPROP 1 LAST LOCATION C695
J 2
(3359 2867);
DISPLAY 0.723404 (3359 2867);
PAINT GREEN (3359 2867);
FORCEPROP 2 LAST $SEC 1
J 2
(3300 2925);
DISPLAY 0.680851 (3300 2925);
PAINT MONO (3300 2925);
DISPLAY INVISIBLE (3300 2925);
FORCEPROP 2 LAST CDS_SEC 1
J 2
(3300 2925);
DISPLAY 0.680851 (3300 2925);
DISPLAY INVISIBLE (3300 2925);
FORCEPROP 2 LASTPIN (3200 2850) $PN 1
J 0
(3210 2860);
DISPLAY 0.808511 (3210 2860);
FORCEPROP 2 LASTPIN (3050 2850) $PN 2
J 2
(3040 2860);
DISPLAY 0.808511 (3040 2860);
FORCEPROP 2 LAST VALUE DIFF BUS_0.22UF
J 2
(2975 2850);
DISPLAY 0.553191 (2975 2850);
FORCEPROP 2 LAST TOLERANCE 20%
J 2
(3050 2900);
DISPLAY 0.553191 (3050 2900);
DISPLAY INVISIBLE (3050 2900);
FORCEPROP 2 LAST PACK_TYPE C0201
J 2
(2950 2900);
DISPLAY 0.553191 (2950 2900);
DISPLAY INVISIBLE (2950 2900);
FORCEPROP 1 LAST MATERIAL X6S
J 2
(3134 2929);
DISPLAY 0.574468 (3134 2929);
PAINT GREEN (3134 2929);
DISPLAY INVISIBLE (3134 2929);
FORCEPROP 2 LAST VOLTAGE 6.3V
J 2
(2775 2900);
DISPLAY 0.553191 (2775 2900);
DISPLAY INVISIBLE (2775 2900);
FORCEPROP 1 LAST CDS_LMAN_SYM_OUTLINE -25,50,25,-50
J 2
(3125 2850);
DISPLAY 0.468085 (3125 2850);
PAINT GREEN (3125 2850);
DISPLAY INVISIBLE (3125 2850);
FORCEPROP 2 LAST CDS_LIB pure_quanta
J 2
(3125 2850);
DISPLAY INVISIBLE (3125 2850);
FORCEPROP 1 LAST PIN_NAMES_ROTATE TRUE
J 2
(3125 2850);
DISPLAY 0.489362 (3125 2850);
PAINT GREEN (3125 2850);
DISPLAY INVISIBLE (3125 2850);
FORCEPROP 1 LAST PART_NUMBER SP_CH4221MEE01
J 2
(3009 2938);
DISPLAY 0.574468 (3009 2938);
PAINT GREEN (3009 2938);
DISPLAY INVISIBLE (3009 2938);
FORCEPROP 1 LAST LOCATION C695
J 0
(3375 2925);
DISPLAY 1.021277 (3375 2925);
DISPLAY INVISIBLE (3375 2925);
FORCEPROP 1 LAST PATH I205
J 2
(3125 2850);
DISPLAY 0.723404 (3125 2850);
DISPLAY INVISIBLE (3125 2850);
FORCEADD Q_CAP_DIFFBUS..2
R 2
(3125 2900);
FORCEPROP 1 LAST LOCATION C694
J 2
(3359 2917);
DISPLAY 0.723404 (3359 2917);
PAINT GREEN (3359 2917);
FORCEPROP 2 LAST $SEC 1
J 2
(3300 2975);
DISPLAY 0.680851 (3300 2975);
PAINT MONO (3300 2975);
DISPLAY INVISIBLE (3300 2975);
FORCEPROP 2 LAST CDS_SEC 1
J 2
(3300 2975);
DISPLAY 0.680851 (3300 2975);
DISPLAY INVISIBLE (3300 2975);
FORCEPROP 2 LASTPIN (3200 2900) $PN 1
J 0
(3210 2910);
DISPLAY 0.808511 (3210 2910);
FORCEPROP 2 LASTPIN (3050 2900) $PN 2
J 2
(3040 2910);
DISPLAY 0.808511 (3040 2910);
FORCEPROP 2 LAST VALUE DIFF BUS_0.22UF
J 2
(2975 2900);
DISPLAY 0.553191 (2975 2900);
FORCEPROP 2 LAST TOLERANCE 20%
J 2
(3050 2950);
DISPLAY 0.553191 (3050 2950);
DISPLAY INVISIBLE (3050 2950);
FORCEPROP 2 LAST PACK_TYPE C0201
J 2
(2950 2950);
DISPLAY 0.553191 (2950 2950);
DISPLAY INVISIBLE (2950 2950);
FORCEPROP 1 LAST MATERIAL X6S
J 2
(3134 2979);
DISPLAY 0.574468 (3134 2979);
PAINT GREEN (3134 2979);
DISPLAY INVISIBLE (3134 2979);
FORCEPROP 2 LAST VOLTAGE 6.3V
J 2
(2775 2950);
DISPLAY 0.553191 (2775 2950);
DISPLAY INVISIBLE (2775 2950);
FORCEPROP 2 LAST CDS_LIB pure_quanta
J 2
(3125 2900);
DISPLAY INVISIBLE (3125 2900);
FORCEPROP 1 LAST CDS_LMAN_SYM_OUTLINE -25,50,25,-50
J 2
(3125 2900);
DISPLAY 0.468085 (3125 2900);
PAINT GREEN (3125 2900);
DISPLAY INVISIBLE (3125 2900);
FORCEPROP 1 LAST PIN_NAMES_ROTATE TRUE
J 2
(3125 2900);
DISPLAY 0.489362 (3125 2900);
PAINT GREEN (3125 2900);
DISPLAY INVISIBLE (3125 2900);
FORCEPROP 1 LAST PART_NUMBER SP_CH4221MEE01
J 2
(3009 2988);
DISPLAY 0.574468 (3009 2988);
PAINT GREEN (3009 2988);
DISPLAY INVISIBLE (3009 2988);
FORCEPROP 1 LAST LOCATION C694
J 0
(3375 2975);
DISPLAY 1.021277 (3375 2975);
DISPLAY INVISIBLE (3375 2975);
FORCEPROP 1 LAST PATH I206
J 2
(3125 2900);
DISPLAY 0.723404 (3125 2900);
DISPLAY INVISIBLE (3125 2900);
FORCEADD TAP..1
(3675 2100);
FORCEPROP 3 LASTPIN (3625 2100) SIG_NAME P5E_CPU1_G1_TX_C_DN<3>
J 0
(3635 2110);
DISPLAY 0.659574 (3635 2110);
PAINT MONO (3635 2110);
DISPLAY INVISIBLE (3635 2110);
FORCEPROP 1 LASTPIN (3625 2100) BN 3
J 0
(3613 2108);
DISPLAY 0.680851 (3613 2108);
PAINT GREEN (3613 2108);
FORCEPROP 2 LAST CDS_LIB standard
J 0
(3675 2100);
DISPLAY INVISIBLE (3675 2100);
FORCEPROP 1 LAST BODY_TYPE PLUMBING
J 0
(3675 2150);
DISPLAY 0.872340 (3675 2150);
PAINT GREEN (3675 2150);
DISPLAY INVISIBLE (3675 2150);
FORCEPROP 1 LAST HDL_TAP TRUE
J 0
(4000 1975);
DISPLAY 0.872340 (4000 1975);
DISPLAY INVISIBLE (4000 1975);
FORCEPROP 1 LAST PATH I207
J 0
(3673 2100);
DISPLAY 0.872340 (3673 2100);
PAINT GREEN (3673 2100);
DISPLAY INVISIBLE (3673 2100);
FORCEADD TAP..1
(3675 2300);
FORCEPROP 3 LASTPIN (3625 2300) SIG_NAME P5E_CPU1_G1_TX_C_DN<4>
J 0
(3635 2310);
DISPLAY 0.659574 (3635 2310);
PAINT MONO (3635 2310);
DISPLAY INVISIBLE (3635 2310);
FORCEPROP 1 LASTPIN (3625 2300) BN 4
J 0
(3613 2308);
DISPLAY 0.680851 (3613 2308);
PAINT GREEN (3613 2308);
FORCEPROP 2 LAST CDS_LIB standard
J 0
(3675 2300);
DISPLAY INVISIBLE (3675 2300);
FORCEPROP 1 LAST BODY_TYPE PLUMBING
J 0
(3675 2350);
DISPLAY 0.872340 (3675 2350);
PAINT GREEN (3675 2350);
DISPLAY INVISIBLE (3675 2350);
FORCEPROP 1 LAST HDL_TAP TRUE
J 0
(4000 2175);
DISPLAY 0.872340 (4000 2175);
DISPLAY INVISIBLE (4000 2175);
FORCEPROP 1 LAST PATH I208
J 0
(3673 2300);
DISPLAY 0.872340 (3673 2300);
PAINT GREEN (3673 2300);
DISPLAY INVISIBLE (3673 2300);
FORCEADD TAP..1
(3875 2250);
FORCEPROP 3 LASTPIN (3825 2250) SIG_NAME P5E_CPU1_G1_TX_C_DP<4>
J 0
(3835 2260);
DISPLAY 0.659574 (3835 2260);
PAINT MONO (3835 2260);
DISPLAY INVISIBLE (3835 2260);
FORCEPROP 1 LASTPIN (3825 2250) BN 4
J 0
(3813 2258);
DISPLAY 0.680851 (3813 2258);
PAINT GREEN (3813 2258);
FORCEPROP 2 LAST CDS_LIB standard
J 0
(3875 2250);
DISPLAY INVISIBLE (3875 2250);
FORCEPROP 1 LAST BODY_TYPE PLUMBING
J 0
(3875 2300);
DISPLAY 0.872340 (3875 2300);
PAINT GREEN (3875 2300);
DISPLAY INVISIBLE (3875 2300);
FORCEPROP 1 LAST HDL_TAP TRUE
J 0
(4200 2125);
DISPLAY 0.872340 (4200 2125);
DISPLAY INVISIBLE (4200 2125);
FORCEPROP 1 LAST PATH I209
J 0
(3873 2250);
DISPLAY 0.872340 (3873 2250);
PAINT GREEN (3873 2250);
DISPLAY INVISIBLE (3873 2250);
FORCEADD TAP..1
R 2
(-2350 50);
FORCEPROP 3 LASTPIN (-2300 50) SIG_NAME P3E_CPU0_P4_TX_DN<0>
J 0
(-2290 60);
DISPLAY 0.659574 (-2290 60);
PAINT MONO (-2290 60);
DISPLAY INVISIBLE (-2290 60);
FORCEPROP 1 LASTPIN (-2300 50) BN 0
J 2
(-2288 58);
DISPLAY 0.680851 (-2288 58);
PAINT MONO (-2288 58);
FORCEPROP 2 LAST CDS_LIB standard
J 0
(-2350 50);
DISPLAY INVISIBLE (-2350 50);
FORCEPROP 1 LAST BODY_TYPE PLUMBING
J 2
(-2350 100);
DISPLAY 0.872340 (-2350 100);
PAINT GREEN (-2350 100);
DISPLAY INVISIBLE (-2350 100);
FORCEPROP 1 LAST HDL_TAP TRUE
J 2
(-2675 -75);
DISPLAY 0.872340 (-2675 -75);
DISPLAY INVISIBLE (-2675 -75);
FORCEPROP 1 LAST PATH I21
J 2
(-2348 50);
DISPLAY 0.872340 (-2348 50);
PAINT GREEN (-2348 50);
DISPLAY INVISIBLE (-2348 50);
FORCEADD TAP..1
(3875 2450);
FORCEPROP 3 LASTPIN (3825 2450) SIG_NAME P5E_CPU1_G1_TX_C_DP<5>
J 0
(3835 2460);
DISPLAY 0.659574 (3835 2460);
PAINT MONO (3835 2460);
DISPLAY INVISIBLE (3835 2460);
FORCEPROP 1 LASTPIN (3825 2450) BN 5
J 0
(3813 2458);
DISPLAY 0.680851 (3813 2458);
PAINT GREEN (3813 2458);
FORCEPROP 2 LAST CDS_LIB standard
J 0
(3875 2450);
DISPLAY INVISIBLE (3875 2450);
FORCEPROP 1 LAST BODY_TYPE PLUMBING
J 0
(3875 2500);
DISPLAY 0.872340 (3875 2500);
PAINT GREEN (3875 2500);
DISPLAY INVISIBLE (3875 2500);
FORCEPROP 1 LAST HDL_TAP TRUE
J 0
(4200 2325);
DISPLAY 0.872340 (4200 2325);
DISPLAY INVISIBLE (4200 2325);
FORCEPROP 1 LAST PATH I210
J 0
(3873 2450);
DISPLAY 0.872340 (3873 2450);
PAINT GREEN (3873 2450);
DISPLAY INVISIBLE (3873 2450);
FORCEADD TAP..1
(3675 2700);
FORCEPROP 3 LASTPIN (3625 2700) SIG_NAME P5E_CPU1_G1_TX_C_DN<6>
J 0
(3635 2710);
DISPLAY 0.659574 (3635 2710);
PAINT MONO (3635 2710);
DISPLAY INVISIBLE (3635 2710);
FORCEPROP 1 LASTPIN (3625 2700) BN 6
J 0
(3613 2708);
DISPLAY 0.680851 (3613 2708);
PAINT GREEN (3613 2708);
FORCEPROP 2 LAST CDS_LIB standard
J 0
(3675 2700);
DISPLAY INVISIBLE (3675 2700);
FORCEPROP 1 LAST BODY_TYPE PLUMBING
J 0
(3675 2750);
DISPLAY 0.872340 (3675 2750);
PAINT GREEN (3675 2750);
DISPLAY INVISIBLE (3675 2750);
FORCEPROP 1 LAST HDL_TAP TRUE
J 0
(4000 2575);
DISPLAY 0.872340 (4000 2575);
DISPLAY INVISIBLE (4000 2575);
FORCEPROP 1 LAST PATH I211
J 0
(3673 2700);
DISPLAY 0.872340 (3673 2700);
PAINT GREEN (3673 2700);
DISPLAY INVISIBLE (3673 2700);
FORCEADD TAP..1
(3675 2500);
FORCEPROP 3 LASTPIN (3625 2500) SIG_NAME P5E_CPU1_G1_TX_C_DN<5>
J 0
(3635 2510);
DISPLAY 0.659574 (3635 2510);
PAINT MONO (3635 2510);
DISPLAY INVISIBLE (3635 2510);
FORCEPROP 1 LASTPIN (3625 2500) BN 5
J 0
(3613 2508);
DISPLAY 0.680851 (3613 2508);
PAINT GREEN (3613 2508);
FORCEPROP 2 LAST CDS_LIB standard
J 0
(3675 2500);
DISPLAY INVISIBLE (3675 2500);
FORCEPROP 1 LAST BODY_TYPE PLUMBING
J 0
(3675 2550);
DISPLAY 0.872340 (3675 2550);
PAINT GREEN (3675 2550);
DISPLAY INVISIBLE (3675 2550);
FORCEPROP 1 LAST HDL_TAP TRUE
J 0
(4000 2375);
DISPLAY 0.872340 (4000 2375);
DISPLAY INVISIBLE (4000 2375);
FORCEPROP 1 LAST PATH I212
J 0
(3673 2500);
DISPLAY 0.872340 (3673 2500);
PAINT GREEN (3673 2500);
DISPLAY INVISIBLE (3673 2500);
FORCEADD TAP..1
(3675 2900);
FORCEPROP 3 LASTPIN (3625 2900) SIG_NAME P5E_CPU1_G1_TX_C_DN<7>
J 0
(3635 2910);
DISPLAY 0.659574 (3635 2910);
PAINT MONO (3635 2910);
DISPLAY INVISIBLE (3635 2910);
FORCEPROP 1 LASTPIN (3625 2900) BN 7
J 0
(3613 2908);
DISPLAY 0.680851 (3613 2908);
PAINT GREEN (3613 2908);
FORCEPROP 2 LAST CDS_LIB standard
J 0
(3675 2900);
DISPLAY INVISIBLE (3675 2900);
FORCEPROP 1 LAST BODY_TYPE PLUMBING
J 0
(3675 2950);
DISPLAY 0.872340 (3675 2950);
PAINT GREEN (3675 2950);
DISPLAY INVISIBLE (3675 2950);
FORCEPROP 1 LAST HDL_TAP TRUE
J 0
(4000 2775);
DISPLAY 0.872340 (4000 2775);
DISPLAY INVISIBLE (4000 2775);
FORCEPROP 1 LAST PATH I213
J 0
(3673 2900);
DISPLAY 0.872340 (3673 2900);
PAINT GREEN (3673 2900);
DISPLAY INVISIBLE (3673 2900);
FORCEADD TAP..1
(3875 2650);
FORCEPROP 3 LASTPIN (3825 2650) SIG_NAME P5E_CPU1_G1_TX_C_DP<6>
J 0
(3835 2660);
DISPLAY 0.659574 (3835 2660);
PAINT MONO (3835 2660);
DISPLAY INVISIBLE (3835 2660);
FORCEPROP 1 LASTPIN (3825 2650) BN 6
J 0
(3813 2658);
DISPLAY 0.680851 (3813 2658);
PAINT GREEN (3813 2658);
FORCEPROP 2 LAST CDS_LIB standard
J 0
(3875 2650);
DISPLAY INVISIBLE (3875 2650);
FORCEPROP 1 LAST BODY_TYPE PLUMBING
J 0
(3875 2700);
DISPLAY 0.872340 (3875 2700);
PAINT GREEN (3875 2700);
DISPLAY INVISIBLE (3875 2700);
FORCEPROP 1 LAST HDL_TAP TRUE
J 0
(4200 2525);
DISPLAY 0.872340 (4200 2525);
DISPLAY INVISIBLE (4200 2525);
FORCEPROP 1 LAST PATH I214
J 0
(3873 2650);
DISPLAY 0.872340 (3873 2650);
PAINT GREEN (3873 2650);
DISPLAY INVISIBLE (3873 2650);
FORCEADD TAP..1
(3875 2850);
FORCEPROP 3 LASTPIN (3825 2850) SIG_NAME P5E_CPU1_G1_TX_C_DP<7>
J 0
(3835 2860);
DISPLAY 0.659574 (3835 2860);
PAINT MONO (3835 2860);
DISPLAY INVISIBLE (3835 2860);
FORCEPROP 1 LASTPIN (3825 2850) BN 7
J 0
(3813 2858);
DISPLAY 0.680851 (3813 2858);
PAINT GREEN (3813 2858);
FORCEPROP 2 LAST CDS_LIB standard
J 0
(3875 2850);
DISPLAY INVISIBLE (3875 2850);
FORCEPROP 1 LAST BODY_TYPE PLUMBING
J 0
(3875 2900);
DISPLAY 0.872340 (3875 2900);
PAINT GREEN (3875 2900);
DISPLAY INVISIBLE (3875 2900);
FORCEPROP 1 LAST HDL_TAP TRUE
J 0
(4200 2725);
DISPLAY 0.872340 (4200 2725);
DISPLAY INVISIBLE (4200 2725);
FORCEPROP 1 LAST PATH I215
J 0
(3873 2850);
DISPLAY 0.872340 (3873 2850);
PAINT GREEN (3873 2850);
DISPLAY INVISIBLE (3873 2850);
FORCEADD Q_CAP_DIFFBUS..2
R 2
(3125 3050);
FORCEPROP 1 LAST LOCATION C56
J 2
(3359 3067);
DISPLAY 0.723404 (3359 3067);
PAINT GREEN (3359 3067);
FORCEPROP 2 LAST $SEC 1
J 2
(3300 3125);
DISPLAY 0.680851 (3300 3125);
PAINT MONO (3300 3125);
DISPLAY INVISIBLE (3300 3125);
FORCEPROP 2 LAST CDS_SEC 1
J 2
(3300 3125);
DISPLAY 0.680851 (3300 3125);
DISPLAY INVISIBLE (3300 3125);
FORCEPROP 2 LASTPIN (3200 3050) $PN 1
J 0
(3210 3060);
DISPLAY 0.808511 (3210 3060);
FORCEPROP 2 LASTPIN (3050 3050) $PN 2
J 2
(3040 3060);
DISPLAY 0.808511 (3040 3060);
FORCEPROP 2 LAST VALUE DIFF BUS_0.22UF
J 2
(2975 3050);
DISPLAY 0.553191 (2975 3050);
FORCEPROP 1 LAST CDS_LMAN_SYM_OUTLINE -25,50,25,-50
J 2
(3125 3050);
DISPLAY 0.468085 (3125 3050);
PAINT GREEN (3125 3050);
DISPLAY INVISIBLE (3125 3050);
FORCEPROP 2 LAST CDS_LIB pure_quanta
J 2
(3125 3050);
DISPLAY INVISIBLE (3125 3050);
FORCEPROP 1 LAST PIN_NAMES_ROTATE TRUE
J 2
(3125 3050);
DISPLAY 0.489362 (3125 3050);
PAINT GREEN (3125 3050);
DISPLAY INVISIBLE (3125 3050);
FORCEPROP 2 LAST VOLTAGE 6.3V
J 2
(2775 3100);
DISPLAY 0.553191 (2775 3100);
DISPLAY INVISIBLE (2775 3100);
FORCEPROP 1 LAST MATERIAL X6S
J 2
(3134 3129);
DISPLAY 0.574468 (3134 3129);
PAINT GREEN (3134 3129);
DISPLAY INVISIBLE (3134 3129);
FORCEPROP 2 LAST PACK_TYPE C0201
J 2
(2950 3100);
DISPLAY 0.553191 (2950 3100);
DISPLAY INVISIBLE (2950 3100);
FORCEPROP 2 LAST TOLERANCE 20%
J 2
(3050 3100);
DISPLAY 0.553191 (3050 3100);
DISPLAY INVISIBLE (3050 3100);
FORCEPROP 1 LAST PART_NUMBER SP_CH4221MEE01
J 2
(3009 3138);
DISPLAY 0.574468 (3009 3138);
PAINT GREEN (3009 3138);
DISPLAY INVISIBLE (3009 3138);
FORCEPROP 1 LAST PATH I216
J 2
(3125 3050);
DISPLAY 0.723404 (3125 3050);
DISPLAY INVISIBLE (3125 3050);
FORCEADD Q_CAP_DIFFBUS..2
R 2
(3125 3100);
FORCEPROP 1 LAST LOCATION C692
J 2
(3359 3117);
DISPLAY 0.723404 (3359 3117);
PAINT GREEN (3359 3117);
FORCEPROP 2 LAST $SEC 1
J 2
(3300 3175);
DISPLAY 0.680851 (3300 3175);
PAINT MONO (3300 3175);
DISPLAY INVISIBLE (3300 3175);
FORCEPROP 2 LAST CDS_SEC 1
J 2
(3300 3175);
DISPLAY 0.680851 (3300 3175);
DISPLAY INVISIBLE (3300 3175);
FORCEPROP 2 LASTPIN (3200 3100) $PN 1
J 0
(3210 3110);
DISPLAY 0.808511 (3210 3110);
FORCEPROP 2 LASTPIN (3050 3100) $PN 2
J 2
(3040 3110);
DISPLAY 0.808511 (3040 3110);
FORCEPROP 2 LAST VALUE DIFF BUS_0.22UF
J 2
(2975 3100);
DISPLAY 0.553191 (2975 3100);
FORCEPROP 1 LAST CDS_LMAN_SYM_OUTLINE -25,50,25,-50
J 2
(3125 3100);
DISPLAY 0.468085 (3125 3100);
PAINT GREEN (3125 3100);
DISPLAY INVISIBLE (3125 3100);
FORCEPROP 2 LAST CDS_LIB pure_quanta
J 2
(3125 3100);
DISPLAY INVISIBLE (3125 3100);
FORCEPROP 1 LAST PIN_NAMES_ROTATE TRUE
J 2
(3125 3100);
DISPLAY 0.489362 (3125 3100);
PAINT GREEN (3125 3100);
DISPLAY INVISIBLE (3125 3100);
FORCEPROP 2 LAST VOLTAGE 6.3V
J 2
(2775 3150);
DISPLAY 0.553191 (2775 3150);
DISPLAY INVISIBLE (2775 3150);
FORCEPROP 1 LAST MATERIAL X6S
J 2
(3134 3179);
DISPLAY 0.574468 (3134 3179);
PAINT GREEN (3134 3179);
DISPLAY INVISIBLE (3134 3179);
FORCEPROP 2 LAST PACK_TYPE C0201
J 2
(2950 3150);
DISPLAY 0.553191 (2950 3150);
DISPLAY INVISIBLE (2950 3150);
FORCEPROP 2 LAST TOLERANCE 20%
J 2
(3050 3150);
DISPLAY 0.553191 (3050 3150);
DISPLAY INVISIBLE (3050 3150);
FORCEPROP 1 LAST PART_NUMBER SP_CH4221MEE01
J 2
(3009 3188);
DISPLAY 0.574468 (3009 3188);
PAINT GREEN (3009 3188);
DISPLAY INVISIBLE (3009 3188);
FORCEPROP 1 LAST LOCATION C692
J 0
(3375 3175);
DISPLAY 1.021277 (3375 3175);
DISPLAY INVISIBLE (3375 3175);
FORCEPROP 1 LAST PATH I217
J 2
(3125 3100);
DISPLAY 0.723404 (3125 3100);
DISPLAY INVISIBLE (3125 3100);
FORCEADD Q_CAP_DIFFBUS..2
R 2
(3125 3250);
FORCEPROP 1 LAST LOCATION C691
J 2
(3359 3267);
DISPLAY 0.723404 (3359 3267);
PAINT GREEN (3359 3267);
FORCEPROP 2 LAST $SEC 1
J 2
(3300 3325);
DISPLAY 0.680851 (3300 3325);
PAINT MONO (3300 3325);
DISPLAY INVISIBLE (3300 3325);
FORCEPROP 2 LAST CDS_SEC 1
J 2
(3300 3325);
DISPLAY 0.680851 (3300 3325);
DISPLAY INVISIBLE (3300 3325);
FORCEPROP 2 LASTPIN (3200 3250) $PN 1
J 0
(3210 3260);
DISPLAY 0.808511 (3210 3260);
FORCEPROP 2 LASTPIN (3050 3250) $PN 2
J 2
(3040 3260);
DISPLAY 0.808511 (3040 3260);
FORCEPROP 2 LAST VALUE DIFF BUS_0.22UF
J 2
(2975 3250);
DISPLAY 0.553191 (2975 3250);
FORCEPROP 1 LAST CDS_LMAN_SYM_OUTLINE -25,50,25,-50
J 2
(3125 3250);
DISPLAY 0.468085 (3125 3250);
PAINT GREEN (3125 3250);
DISPLAY INVISIBLE (3125 3250);
FORCEPROP 2 LAST CDS_LIB pure_quanta
J 2
(3125 3250);
DISPLAY INVISIBLE (3125 3250);
FORCEPROP 1 LAST PIN_NAMES_ROTATE TRUE
J 2
(3125 3250);
DISPLAY 0.489362 (3125 3250);
PAINT GREEN (3125 3250);
DISPLAY INVISIBLE (3125 3250);
FORCEPROP 2 LAST VOLTAGE 6.3V
J 2
(2775 3300);
DISPLAY 0.553191 (2775 3300);
DISPLAY INVISIBLE (2775 3300);
FORCEPROP 1 LAST MATERIAL X6S
J 2
(3134 3329);
DISPLAY 0.574468 (3134 3329);
PAINT GREEN (3134 3329);
DISPLAY INVISIBLE (3134 3329);
FORCEPROP 2 LAST PACK_TYPE C0201
J 2
(2950 3300);
DISPLAY 0.553191 (2950 3300);
DISPLAY INVISIBLE (2950 3300);
FORCEPROP 2 LAST TOLERANCE 20%
J 2
(3050 3300);
DISPLAY 0.553191 (3050 3300);
DISPLAY INVISIBLE (3050 3300);
FORCEPROP 1 LAST PART_NUMBER SP_CH4221MEE01
J 2
(3009 3338);
DISPLAY 0.574468 (3009 3338);
PAINT GREEN (3009 3338);
DISPLAY INVISIBLE (3009 3338);
FORCEPROP 1 LAST LOCATION C691
J 0
(3375 3325);
DISPLAY 1.021277 (3375 3325);
DISPLAY INVISIBLE (3375 3325);
FORCEPROP 1 LAST PATH I218
J 2
(3125 3250);
DISPLAY 0.723404 (3125 3250);
DISPLAY INVISIBLE (3125 3250);
FORCEADD Q_CAP_DIFFBUS..2
R 2
(3125 3300);
FORCEPROP 1 LAST LOCATION C690
J 2
(3359 3317);
DISPLAY 0.723404 (3359 3317);
PAINT GREEN (3359 3317);
FORCEPROP 2 LAST $SEC 1
J 2
(3300 3375);
DISPLAY 0.680851 (3300 3375);
PAINT MONO (3300 3375);
DISPLAY INVISIBLE (3300 3375);
FORCEPROP 2 LAST CDS_SEC 1
J 2
(3300 3375);
DISPLAY 0.680851 (3300 3375);
DISPLAY INVISIBLE (3300 3375);
FORCEPROP 2 LASTPIN (3200 3300) $PN 1
J 0
(3210 3310);
DISPLAY 0.808511 (3210 3310);
FORCEPROP 2 LASTPIN (3050 3300) $PN 2
J 2
(3040 3310);
DISPLAY 0.808511 (3040 3310);
FORCEPROP 2 LAST VALUE DIFF BUS_0.22UF
J 2
(2975 3300);
DISPLAY 0.553191 (2975 3300);
FORCEPROP 2 LAST CDS_LIB pure_quanta
J 2
(3125 3300);
DISPLAY INVISIBLE (3125 3300);
FORCEPROP 1 LAST CDS_LMAN_SYM_OUTLINE -25,50,25,-50
J 2
(3125 3300);
DISPLAY 0.468085 (3125 3300);
PAINT GREEN (3125 3300);
DISPLAY INVISIBLE (3125 3300);
FORCEPROP 1 LAST PIN_NAMES_ROTATE TRUE
J 2
(3125 3300);
DISPLAY 0.489362 (3125 3300);
PAINT GREEN (3125 3300);
DISPLAY INVISIBLE (3125 3300);
FORCEPROP 2 LAST VOLTAGE 6.3V
J 2
(2775 3350);
DISPLAY 0.553191 (2775 3350);
DISPLAY INVISIBLE (2775 3350);
FORCEPROP 1 LAST MATERIAL X6S
J 2
(3134 3379);
DISPLAY 0.574468 (3134 3379);
PAINT GREEN (3134 3379);
DISPLAY INVISIBLE (3134 3379);
FORCEPROP 2 LAST PACK_TYPE C0201
J 2
(2950 3350);
DISPLAY 0.553191 (2950 3350);
DISPLAY INVISIBLE (2950 3350);
FORCEPROP 2 LAST TOLERANCE 20%
J 2
(3050 3350);
DISPLAY 0.553191 (3050 3350);
DISPLAY INVISIBLE (3050 3350);
FORCEPROP 1 LAST PART_NUMBER SP_CH4221MEE01
J 2
(3009 3388);
DISPLAY 0.574468 (3009 3388);
PAINT GREEN (3009 3388);
DISPLAY INVISIBLE (3009 3388);
FORCEPROP 1 LAST LOCATION C690
J 0
(3375 3375);
DISPLAY 1.021277 (3375 3375);
DISPLAY INVISIBLE (3375 3375);
FORCEPROP 1 LAST PATH I219
J 2
(3125 3300);
DISPLAY 0.723404 (3125 3300);
DISPLAY INVISIBLE (3125 3300);
FORCEADD TAP..1
R 2
(-2100 100);
FORCEPROP 3 LASTPIN (-2050 100) SIG_NAME P3E_CPU0_P4_TX_DP<0>
J 0
(-2040 110);
DISPLAY 0.659574 (-2040 110);
PAINT MONO (-2040 110);
DISPLAY INVISIBLE (-2040 110);
FORCEPROP 1 LASTPIN (-2050 100) BN 0
J 2
(-2038 108);
DISPLAY 0.680851 (-2038 108);
PAINT MONO (-2038 108);
FORCEPROP 2 LAST CDS_LIB standard
J 0
(-2100 100);
DISPLAY INVISIBLE (-2100 100);
FORCEPROP 1 LAST BODY_TYPE PLUMBING
J 2
(-2100 150);
DISPLAY 0.872340 (-2100 150);
PAINT GREEN (-2100 150);
DISPLAY INVISIBLE (-2100 150);
FORCEPROP 1 LAST HDL_TAP TRUE
J 2
(-2425 -25);
DISPLAY 0.872340 (-2425 -25);
DISPLAY INVISIBLE (-2425 -25);
FORCEPROP 1 LAST PATH I22
J 2
(-2098 100);
DISPLAY 0.872340 (-2098 100);
PAINT GREEN (-2098 100);
DISPLAY INVISIBLE (-2098 100);
FORCEADD Q_CAP_DIFFBUS..2
R 2
(3125 3500);
FORCEPROP 1 LAST LOCATION C688
J 2
(3359 3517);
DISPLAY 0.723404 (3359 3517);
PAINT GREEN (3359 3517);
FORCEPROP 2 LAST $SEC 1
J 2
(3300 3575);
DISPLAY 0.680851 (3300 3575);
PAINT MONO (3300 3575);
DISPLAY INVISIBLE (3300 3575);
FORCEPROP 2 LAST CDS_SEC 1
J 2
(3300 3575);
DISPLAY 0.680851 (3300 3575);
DISPLAY INVISIBLE (3300 3575);
FORCEPROP 2 LASTPIN (3200 3500) $PN 1
J 0
(3210 3510);
DISPLAY 0.808511 (3210 3510);
FORCEPROP 2 LASTPIN (3050 3500) $PN 2
J 2
(3040 3510);
DISPLAY 0.808511 (3040 3510);
FORCEPROP 2 LAST VALUE DIFF BUS_0.22UF
J 2
(2975 3500);
DISPLAY 0.553191 (2975 3500);
FORCEPROP 1 LAST CDS_LMAN_SYM_OUTLINE -25,50,25,-50
J 2
(3125 3500);
DISPLAY 0.468085 (3125 3500);
PAINT GREEN (3125 3500);
DISPLAY INVISIBLE (3125 3500);
FORCEPROP 2 LAST CDS_LIB pure_quanta
J 2
(3125 3500);
DISPLAY INVISIBLE (3125 3500);
FORCEPROP 1 LAST PIN_NAMES_ROTATE TRUE
J 2
(3125 3500);
DISPLAY 0.489362 (3125 3500);
PAINT GREEN (3125 3500);
DISPLAY INVISIBLE (3125 3500);
FORCEPROP 2 LAST VOLTAGE 6.3V
J 2
(2775 3550);
DISPLAY 0.553191 (2775 3550);
DISPLAY INVISIBLE (2775 3550);
FORCEPROP 1 LAST MATERIAL X6S
J 2
(3134 3579);
DISPLAY 0.574468 (3134 3579);
PAINT GREEN (3134 3579);
DISPLAY INVISIBLE (3134 3579);
FORCEPROP 2 LAST PACK_TYPE C0201
J 2
(2950 3550);
DISPLAY 0.553191 (2950 3550);
DISPLAY INVISIBLE (2950 3550);
FORCEPROP 2 LAST TOLERANCE 20%
J 2
(3050 3550);
DISPLAY 0.553191 (3050 3550);
DISPLAY INVISIBLE (3050 3550);
FORCEPROP 1 LAST PART_NUMBER SP_CH4221MEE01
J 2
(3009 3588);
DISPLAY 0.574468 (3009 3588);
PAINT GREEN (3009 3588);
DISPLAY INVISIBLE (3009 3588);
FORCEPROP 1 LAST LOCATION C688
J 0
(3375 3575);
DISPLAY 1.021277 (3375 3575);
DISPLAY INVISIBLE (3375 3575);
FORCEPROP 1 LAST PATH I220
J 2
(3125 3500);
DISPLAY 0.723404 (3125 3500);
DISPLAY INVISIBLE (3125 3500);
FORCEADD Q_CAP_DIFFBUS..2
R 2
(3125 3450);
FORCEPROP 1 LAST LOCATION C689
J 2
(3359 3467);
DISPLAY 0.723404 (3359 3467);
PAINT GREEN (3359 3467);
FORCEPROP 2 LAST $SEC 1
J 2
(3300 3525);
DISPLAY 0.680851 (3300 3525);
PAINT MONO (3300 3525);
DISPLAY INVISIBLE (3300 3525);
FORCEPROP 2 LAST CDS_SEC 1
J 2
(3300 3525);
DISPLAY 0.680851 (3300 3525);
DISPLAY INVISIBLE (3300 3525);
FORCEPROP 2 LASTPIN (3200 3450) $PN 1
J 0
(3210 3460);
DISPLAY 0.808511 (3210 3460);
FORCEPROP 2 LASTPIN (3050 3450) $PN 2
J 2
(3040 3460);
DISPLAY 0.808511 (3040 3460);
FORCEPROP 2 LAST VALUE DIFF BUS_0.22UF
J 2
(2975 3450);
DISPLAY 0.553191 (2975 3450);
FORCEPROP 1 LAST CDS_LMAN_SYM_OUTLINE -25,50,25,-50
J 2
(3125 3450);
DISPLAY 0.468085 (3125 3450);
PAINT GREEN (3125 3450);
DISPLAY INVISIBLE (3125 3450);
FORCEPROP 2 LAST CDS_LIB pure_quanta
J 2
(3125 3450);
DISPLAY INVISIBLE (3125 3450);
FORCEPROP 1 LAST PIN_NAMES_ROTATE TRUE
J 2
(3125 3450);
DISPLAY 0.489362 (3125 3450);
PAINT GREEN (3125 3450);
DISPLAY INVISIBLE (3125 3450);
FORCEPROP 2 LAST VOLTAGE 6.3V
J 2
(2775 3500);
DISPLAY 0.553191 (2775 3500);
DISPLAY INVISIBLE (2775 3500);
FORCEPROP 1 LAST MATERIAL X6S
J 2
(3134 3529);
DISPLAY 0.574468 (3134 3529);
PAINT GREEN (3134 3529);
DISPLAY INVISIBLE (3134 3529);
FORCEPROP 2 LAST PACK_TYPE C0201
J 2
(2950 3500);
DISPLAY 0.553191 (2950 3500);
DISPLAY INVISIBLE (2950 3500);
FORCEPROP 2 LAST TOLERANCE 20%
J 2
(3050 3500);
DISPLAY 0.553191 (3050 3500);
DISPLAY INVISIBLE (3050 3500);
FORCEPROP 1 LAST PART_NUMBER SP_CH4221MEE01
J 2
(3009 3538);
DISPLAY 0.574468 (3009 3538);
PAINT GREEN (3009 3538);
DISPLAY INVISIBLE (3009 3538);
FORCEPROP 1 LAST LOCATION C689
J 0
(3375 3525);
DISPLAY 1.021277 (3375 3525);
DISPLAY INVISIBLE (3375 3525);
FORCEPROP 1 LAST PATH I221
J 2
(3125 3450);
DISPLAY 0.723404 (3125 3450);
DISPLAY INVISIBLE (3125 3450);
FORCEADD Q_CAP_DIFFBUS..2
R 2
(3125 3650);
FORCEPROP 1 LAST LOCATION C687
J 2
(3359 3667);
DISPLAY 0.723404 (3359 3667);
PAINT GREEN (3359 3667);
FORCEPROP 2 LAST $SEC 1
J 2
(3300 3725);
DISPLAY 0.680851 (3300 3725);
PAINT MONO (3300 3725);
DISPLAY INVISIBLE (3300 3725);
FORCEPROP 2 LAST CDS_SEC 1
J 2
(3300 3725);
DISPLAY 0.680851 (3300 3725);
DISPLAY INVISIBLE (3300 3725);
FORCEPROP 2 LASTPIN (3200 3650) $PN 1
J 0
(3210 3660);
DISPLAY 0.808511 (3210 3660);
FORCEPROP 2 LASTPIN (3050 3650) $PN 2
J 2
(3040 3660);
DISPLAY 0.808511 (3040 3660);
FORCEPROP 2 LAST VALUE DIFF BUS_0.22UF
J 2
(2975 3650);
DISPLAY 0.553191 (2975 3650);
FORCEPROP 2 LAST CDS_LIB pure_quanta
J 2
(3125 3650);
DISPLAY INVISIBLE (3125 3650);
FORCEPROP 1 LAST CDS_LMAN_SYM_OUTLINE -25,50,25,-50
J 2
(3125 3650);
DISPLAY 0.468085 (3125 3650);
PAINT GREEN (3125 3650);
DISPLAY INVISIBLE (3125 3650);
FORCEPROP 1 LAST PIN_NAMES_ROTATE TRUE
J 2
(3125 3650);
DISPLAY 0.489362 (3125 3650);
PAINT GREEN (3125 3650);
DISPLAY INVISIBLE (3125 3650);
FORCEPROP 2 LAST VOLTAGE 6.3V
J 2
(2775 3700);
DISPLAY 0.553191 (2775 3700);
DISPLAY INVISIBLE (2775 3700);
FORCEPROP 1 LAST MATERIAL X6S
J 2
(3134 3729);
DISPLAY 0.574468 (3134 3729);
PAINT GREEN (3134 3729);
DISPLAY INVISIBLE (3134 3729);
FORCEPROP 2 LAST PACK_TYPE C0201
J 2
(2950 3700);
DISPLAY 0.553191 (2950 3700);
DISPLAY INVISIBLE (2950 3700);
FORCEPROP 2 LAST TOLERANCE 20%
J 2
(3050 3700);
DISPLAY 0.553191 (3050 3700);
DISPLAY INVISIBLE (3050 3700);
FORCEPROP 1 LAST PART_NUMBER SP_CH4221MEE01
J 2
(3009 3738);
DISPLAY 0.574468 (3009 3738);
PAINT GREEN (3009 3738);
DISPLAY INVISIBLE (3009 3738);
FORCEPROP 1 LAST LOCATION C687
J 0
(3375 3725);
DISPLAY 1.021277 (3375 3725);
DISPLAY INVISIBLE (3375 3725);
FORCEPROP 1 LAST PATH I222
J 2
(3125 3650);
DISPLAY 0.723404 (3125 3650);
DISPLAY INVISIBLE (3125 3650);
FORCEADD Q_CAP_DIFFBUS..2
R 2
(3125 3700);
FORCEPROP 1 LAST LOCATION C686
J 2
(3359 3717);
DISPLAY 0.723404 (3359 3717);
PAINT GREEN (3359 3717);
FORCEPROP 2 LAST $SEC 1
J 2
(3300 3775);
DISPLAY 0.680851 (3300 3775);
PAINT MONO (3300 3775);
DISPLAY INVISIBLE (3300 3775);
FORCEPROP 2 LAST CDS_SEC 1
J 2
(3300 3775);
DISPLAY 0.680851 (3300 3775);
DISPLAY INVISIBLE (3300 3775);
FORCEPROP 2 LASTPIN (3200 3700) $PN 1
J 0
(3210 3710);
DISPLAY 0.808511 (3210 3710);
FORCEPROP 2 LASTPIN (3050 3700) $PN 2
J 2
(3040 3710);
DISPLAY 0.808511 (3040 3710);
FORCEPROP 2 LAST VALUE DIFF BUS_0.22UF
J 2
(2975 3700);
DISPLAY 0.553191 (2975 3700);
FORCEPROP 2 LAST CDS_LIB pure_quanta
J 2
(3125 3700);
DISPLAY INVISIBLE (3125 3700);
FORCEPROP 1 LAST CDS_LMAN_SYM_OUTLINE -25,50,25,-50
J 2
(3125 3700);
DISPLAY 0.468085 (3125 3700);
PAINT GREEN (3125 3700);
DISPLAY INVISIBLE (3125 3700);
FORCEPROP 1 LAST PIN_NAMES_ROTATE TRUE
J 2
(3125 3700);
DISPLAY 0.489362 (3125 3700);
PAINT GREEN (3125 3700);
DISPLAY INVISIBLE (3125 3700);
FORCEPROP 2 LAST VOLTAGE 6.3V
J 2
(2775 3750);
DISPLAY 0.553191 (2775 3750);
DISPLAY INVISIBLE (2775 3750);
FORCEPROP 1 LAST MATERIAL X6S
J 2
(3134 3779);
DISPLAY 0.574468 (3134 3779);
PAINT GREEN (3134 3779);
DISPLAY INVISIBLE (3134 3779);
FORCEPROP 2 LAST PACK_TYPE C0201
J 2
(2950 3750);
DISPLAY 0.553191 (2950 3750);
DISPLAY INVISIBLE (2950 3750);
FORCEPROP 2 LAST TOLERANCE 20%
J 2
(3050 3750);
DISPLAY 0.553191 (3050 3750);
DISPLAY INVISIBLE (3050 3750);
FORCEPROP 1 LAST PART_NUMBER SP_CH4221MEE01
J 2
(3009 3788);
DISPLAY 0.574468 (3009 3788);
PAINT GREEN (3009 3788);
DISPLAY INVISIBLE (3009 3788);
FORCEPROP 1 LAST LOCATION C686
J 0
(3375 3775);
DISPLAY 1.021277 (3375 3775);
DISPLAY INVISIBLE (3375 3775);
FORCEPROP 1 LAST PATH I223
J 2
(3125 3700);
DISPLAY 0.723404 (3125 3700);
DISPLAY INVISIBLE (3125 3700);
FORCEADD Q_CAP_DIFFBUS..2
R 2
(3125 3850);
FORCEPROP 1 LAST LOCATION C685
J 2
(3359 3867);
DISPLAY 0.723404 (3359 3867);
PAINT GREEN (3359 3867);
FORCEPROP 2 LAST $SEC 1
J 2
(3300 3925);
DISPLAY 0.680851 (3300 3925);
PAINT MONO (3300 3925);
DISPLAY INVISIBLE (3300 3925);
FORCEPROP 2 LAST CDS_SEC 1
J 2
(3300 3925);
DISPLAY 0.680851 (3300 3925);
DISPLAY INVISIBLE (3300 3925);
FORCEPROP 2 LASTPIN (3200 3850) $PN 1
J 0
(3210 3860);
DISPLAY 0.808511 (3210 3860);
FORCEPROP 2 LASTPIN (3050 3850) $PN 2
J 2
(3040 3860);
DISPLAY 0.808511 (3040 3860);
FORCEPROP 2 LAST VALUE DIFF BUS_0.22UF
J 2
(2975 3850);
DISPLAY 0.553191 (2975 3850);
FORCEPROP 1 LAST CDS_LMAN_SYM_OUTLINE -25,50,25,-50
J 2
(3125 3850);
DISPLAY 0.468085 (3125 3850);
PAINT GREEN (3125 3850);
DISPLAY INVISIBLE (3125 3850);
FORCEPROP 2 LAST CDS_LIB pure_quanta
J 2
(3125 3850);
DISPLAY INVISIBLE (3125 3850);
FORCEPROP 1 LAST PIN_NAMES_ROTATE TRUE
J 2
(3125 3850);
DISPLAY 0.489362 (3125 3850);
PAINT GREEN (3125 3850);
DISPLAY INVISIBLE (3125 3850);
FORCEPROP 2 LAST VOLTAGE 6.3V
J 2
(2775 3900);
DISPLAY 0.553191 (2775 3900);
DISPLAY INVISIBLE (2775 3900);
FORCEPROP 1 LAST MATERIAL X6S
J 2
(3134 3929);
DISPLAY 0.574468 (3134 3929);
PAINT GREEN (3134 3929);
DISPLAY INVISIBLE (3134 3929);
FORCEPROP 2 LAST PACK_TYPE C0201
J 2
(2950 3900);
DISPLAY 0.553191 (2950 3900);
DISPLAY INVISIBLE (2950 3900);
FORCEPROP 2 LAST TOLERANCE 20%
J 2
(3050 3900);
DISPLAY 0.553191 (3050 3900);
DISPLAY INVISIBLE (3050 3900);
FORCEPROP 1 LAST PART_NUMBER SP_CH4221MEE01
J 2
(3009 3938);
DISPLAY 0.574468 (3009 3938);
PAINT GREEN (3009 3938);
DISPLAY INVISIBLE (3009 3938);
FORCEPROP 1 LAST LOCATION C685
J 0
(3375 3925);
DISPLAY 1.021277 (3375 3925);
DISPLAY INVISIBLE (3375 3925);
FORCEPROP 1 LAST PATH I224
J 2
(3125 3850);
DISPLAY 0.723404 (3125 3850);
DISPLAY INVISIBLE (3125 3850);
FORCEADD Q_CAP_DIFFBUS..2
R 2
(3125 3900);
FORCEPROP 1 LAST LOCATION C684
J 2
(3359 3917);
DISPLAY 0.723404 (3359 3917);
PAINT GREEN (3359 3917);
FORCEPROP 2 LAST $SEC 1
J 2
(3300 3975);
DISPLAY 0.680851 (3300 3975);
PAINT MONO (3300 3975);
DISPLAY INVISIBLE (3300 3975);
FORCEPROP 2 LAST CDS_SEC 1
J 2
(3300 3975);
DISPLAY 0.680851 (3300 3975);
DISPLAY INVISIBLE (3300 3975);
FORCEPROP 2 LASTPIN (3200 3900) $PN 1
J 0
(3210 3910);
DISPLAY 0.808511 (3210 3910);
FORCEPROP 2 LASTPIN (3050 3900) $PN 2
J 2
(3040 3910);
DISPLAY 0.808511 (3040 3910);
FORCEPROP 2 LAST VALUE DIFF BUS_0.22UF
J 2
(2975 3900);
DISPLAY 0.553191 (2975 3900);
FORCEPROP 1 LAST CDS_LMAN_SYM_OUTLINE -25,50,25,-50
J 2
(3125 3900);
DISPLAY 0.468085 (3125 3900);
PAINT GREEN (3125 3900);
DISPLAY INVISIBLE (3125 3900);
FORCEPROP 2 LAST CDS_LIB pure_quanta
J 2
(3125 3900);
DISPLAY INVISIBLE (3125 3900);
FORCEPROP 1 LAST PIN_NAMES_ROTATE TRUE
J 2
(3125 3900);
DISPLAY 0.489362 (3125 3900);
PAINT GREEN (3125 3900);
DISPLAY INVISIBLE (3125 3900);
FORCEPROP 2 LAST VOLTAGE 6.3V
J 2
(2775 3950);
DISPLAY 0.553191 (2775 3950);
DISPLAY INVISIBLE (2775 3950);
FORCEPROP 1 LAST MATERIAL X6S
J 2
(3134 3979);
DISPLAY 0.574468 (3134 3979);
PAINT GREEN (3134 3979);
DISPLAY INVISIBLE (3134 3979);
FORCEPROP 2 LAST PACK_TYPE C0201
J 2
(2950 3950);
DISPLAY 0.553191 (2950 3950);
DISPLAY INVISIBLE (2950 3950);
FORCEPROP 2 LAST TOLERANCE 20%
J 2
(3050 3950);
DISPLAY 0.553191 (3050 3950);
DISPLAY INVISIBLE (3050 3950);
FORCEPROP 1 LAST PART_NUMBER SP_CH4221MEE01
J 2
(3009 3988);
DISPLAY 0.574468 (3009 3988);
PAINT GREEN (3009 3988);
DISPLAY INVISIBLE (3009 3988);
FORCEPROP 1 LAST LOCATION C684
J 0
(3375 3975);
DISPLAY 1.021277 (3375 3975);
DISPLAY INVISIBLE (3375 3975);
FORCEPROP 1 LAST PATH I225
J 2
(3125 3900);
DISPLAY 0.723404 (3125 3900);
DISPLAY INVISIBLE (3125 3900);
FORCEADD TAP..1
(3675 3100);
FORCEPROP 3 LASTPIN (3625 3100) SIG_NAME P5E_CPU1_G1_TX_C_DN<8>
J 0
(3635 3110);
DISPLAY 0.659574 (3635 3110);
PAINT MONO (3635 3110);
DISPLAY INVISIBLE (3635 3110);
FORCEPROP 1 LASTPIN (3625 3100) BN 8
J 0
(3613 3108);
DISPLAY 0.680851 (3613 3108);
PAINT GREEN (3613 3108);
FORCEPROP 2 LAST CDS_LIB standard
J 0
(3675 3100);
DISPLAY INVISIBLE (3675 3100);
FORCEPROP 1 LAST BODY_TYPE PLUMBING
J 0
(3675 3150);
DISPLAY 0.872340 (3675 3150);
PAINT GREEN (3675 3150);
DISPLAY INVISIBLE (3675 3150);
FORCEPROP 1 LAST HDL_TAP TRUE
J 0
(4000 2975);
DISPLAY 0.872340 (4000 2975);
DISPLAY INVISIBLE (4000 2975);
FORCEPROP 1 LAST PATH I226
J 0
(3673 3100);
DISPLAY 0.872340 (3673 3100);
PAINT GREEN (3673 3100);
DISPLAY INVISIBLE (3673 3100);
FORCEADD TAP..1
(3675 3300);
FORCEPROP 3 LASTPIN (3625 3300) SIG_NAME P5E_CPU1_G1_TX_C_DN<9>
J 0
(3635 3310);
DISPLAY 0.659574 (3635 3310);
PAINT MONO (3635 3310);
DISPLAY INVISIBLE (3635 3310);
FORCEPROP 1 LASTPIN (3625 3300) BN 9
J 0
(3613 3308);
DISPLAY 0.680851 (3613 3308);
PAINT GREEN (3613 3308);
FORCEPROP 2 LAST CDS_LIB standard
J 0
(3675 3300);
DISPLAY INVISIBLE (3675 3300);
FORCEPROP 1 LAST BODY_TYPE PLUMBING
J 0
(3675 3350);
DISPLAY 0.872340 (3675 3350);
PAINT GREEN (3675 3350);
DISPLAY INVISIBLE (3675 3350);
FORCEPROP 1 LAST HDL_TAP TRUE
J 0
(4000 3175);
DISPLAY 0.872340 (4000 3175);
DISPLAY INVISIBLE (4000 3175);
FORCEPROP 1 LAST PATH I227
J 0
(3673 3300);
DISPLAY 0.872340 (3673 3300);
PAINT GREEN (3673 3300);
DISPLAY INVISIBLE (3673 3300);
FORCEADD TAP..1
(3675 3500);
FORCEPROP 3 LASTPIN (3625 3500) SIG_NAME P5E_CPU1_G1_TX_C_DN<10>
J 0
(3635 3510);
DISPLAY 0.659574 (3635 3510);
PAINT MONO (3635 3510);
DISPLAY INVISIBLE (3635 3510);
FORCEPROP 1 LASTPIN (3625 3500) BN 10
J 0
(3613 3508);
DISPLAY 0.680851 (3613 3508);
PAINT GREEN (3613 3508);
FORCEPROP 2 LAST CDS_LIB standard
J 0
(3675 3500);
DISPLAY INVISIBLE (3675 3500);
FORCEPROP 1 LAST BODY_TYPE PLUMBING
J 0
(3675 3550);
DISPLAY 0.872340 (3675 3550);
PAINT GREEN (3675 3550);
DISPLAY INVISIBLE (3675 3550);
FORCEPROP 1 LAST HDL_TAP TRUE
J 0
(4000 3375);
DISPLAY 0.872340 (4000 3375);
DISPLAY INVISIBLE (4000 3375);
FORCEPROP 1 LAST PATH I228
J 0
(3673 3500);
DISPLAY 0.872340 (3673 3500);
PAINT GREEN (3673 3500);
DISPLAY INVISIBLE (3673 3500);
FORCEADD TAP..1
(3875 3250);
FORCEPROP 3 LASTPIN (3825 3250) SIG_NAME P5E_CPU1_G1_TX_C_DP<9>
J 0
(3835 3260);
DISPLAY 0.659574 (3835 3260);
PAINT MONO (3835 3260);
DISPLAY INVISIBLE (3835 3260);
FORCEPROP 1 LASTPIN (3825 3250) BN 9
J 0
(3813 3258);
DISPLAY 0.680851 (3813 3258);
PAINT GREEN (3813 3258);
FORCEPROP 2 LAST CDS_LIB standard
J 0
(3875 3250);
DISPLAY INVISIBLE (3875 3250);
FORCEPROP 1 LAST BODY_TYPE PLUMBING
J 0
(3875 3300);
DISPLAY 0.872340 (3875 3300);
PAINT GREEN (3875 3300);
DISPLAY INVISIBLE (3875 3300);
FORCEPROP 1 LAST HDL_TAP TRUE
J 0
(4200 3125);
DISPLAY 0.872340 (4200 3125);
DISPLAY INVISIBLE (4200 3125);
FORCEPROP 1 LAST PATH I229
J 0
(3873 3250);
DISPLAY 0.872340 (3873 3250);
PAINT GREEN (3873 3250);
DISPLAY INVISIBLE (3873 3250);
FORCEADD TAP..1
R 2
(-2500 1425);
FORCEPROP 3 LASTPIN (-2450 1425) SIG_NAME P5E_CPU1_P3_TX_DP<0>
J 0
(-2440 1435);
DISPLAY 0.659574 (-2440 1435);
PAINT MONO (-2440 1435);
DISPLAY INVISIBLE (-2440 1435);
FORCEPROP 1 LASTPIN (-2450 1425) BN 0
J 2
(-2438 1433);
DISPLAY 0.680851 (-2438 1433);
PAINT GREEN (-2438 1433);
FORCEPROP 2 LAST CDS_LIB standard
J 0
(-2500 1425);
DISPLAY INVISIBLE (-2500 1425);
FORCEPROP 1 LAST BODY_TYPE PLUMBING
J 2
(-2500 1475);
DISPLAY 0.872340 (-2500 1475);
PAINT GREEN (-2500 1475);
DISPLAY INVISIBLE (-2500 1475);
FORCEPROP 1 LAST HDL_TAP TRUE
J 2
(-2825 1300);
DISPLAY 0.872340 (-2825 1300);
DISPLAY INVISIBLE (-2825 1300);
FORCEPROP 1 LAST PATH I23
J 2
(-2498 1425);
DISPLAY 0.872340 (-2498 1425);
PAINT GREEN (-2498 1425);
DISPLAY INVISIBLE (-2498 1425);
FORCEADD TAP..1
(3875 3050);
FORCEPROP 3 LASTPIN (3825 3050) SIG_NAME P5E_CPU1_G1_TX_C_DP<8>
J 0
(3835 3060);
DISPLAY 0.659574 (3835 3060);
PAINT MONO (3835 3060);
DISPLAY INVISIBLE (3835 3060);
FORCEPROP 1 LASTPIN (3825 3050) BN 8
J 0
(3813 3058);
DISPLAY 0.680851 (3813 3058);
PAINT GREEN (3813 3058);
FORCEPROP 2 LAST CDS_LIB standard
J 0
(3875 3050);
DISPLAY INVISIBLE (3875 3050);
FORCEPROP 1 LAST BODY_TYPE PLUMBING
J 0
(3875 3100);
DISPLAY 0.872340 (3875 3100);
PAINT GREEN (3875 3100);
DISPLAY INVISIBLE (3875 3100);
FORCEPROP 1 LAST HDL_TAP TRUE
J 0
(4200 2925);
DISPLAY 0.872340 (4200 2925);
DISPLAY INVISIBLE (4200 2925);
FORCEPROP 1 LAST PATH I230
J 0
(3873 3050);
DISPLAY 0.872340 (3873 3050);
PAINT GREEN (3873 3050);
DISPLAY INVISIBLE (3873 3050);
FORCEADD TAP..1
(3875 3450);
FORCEPROP 3 LASTPIN (3825 3450) SIG_NAME P5E_CPU1_G1_TX_C_DP<10>
J 0
(3835 3460);
DISPLAY 0.659574 (3835 3460);
PAINT MONO (3835 3460);
DISPLAY INVISIBLE (3835 3460);
FORCEPROP 1 LASTPIN (3825 3450) BN 10
J 0
(3813 3458);
DISPLAY 0.680851 (3813 3458);
PAINT GREEN (3813 3458);
FORCEPROP 2 LAST CDS_LIB standard
J 0
(3875 3450);
DISPLAY INVISIBLE (3875 3450);
FORCEPROP 1 LAST BODY_TYPE PLUMBING
J 0
(3875 3500);
DISPLAY 0.872340 (3875 3500);
PAINT GREEN (3875 3500);
DISPLAY INVISIBLE (3875 3500);
FORCEPROP 1 LAST HDL_TAP TRUE
J 0
(4200 3325);
DISPLAY 0.872340 (4200 3325);
DISPLAY INVISIBLE (4200 3325);
FORCEPROP 1 LAST PATH I231
J 0
(3873 3450);
DISPLAY 0.872340 (3873 3450);
PAINT GREEN (3873 3450);
DISPLAY INVISIBLE (3873 3450);
FORCEADD TAP..1
(3675 3700);
FORCEPROP 3 LASTPIN (3625 3700) SIG_NAME P5E_CPU1_G1_TX_C_DN<11>
J 0
(3635 3710);
DISPLAY 0.659574 (3635 3710);
PAINT MONO (3635 3710);
DISPLAY INVISIBLE (3635 3710);
FORCEPROP 1 LASTPIN (3625 3700) BN 11
J 0
(3613 3708);
DISPLAY 0.680851 (3613 3708);
PAINT GREEN (3613 3708);
FORCEPROP 2 LAST CDS_LIB standard
J 0
(3675 3700);
DISPLAY INVISIBLE (3675 3700);
FORCEPROP 1 LAST BODY_TYPE PLUMBING
J 0
(3675 3750);
DISPLAY 0.872340 (3675 3750);
PAINT GREEN (3675 3750);
DISPLAY INVISIBLE (3675 3750);
FORCEPROP 1 LAST HDL_TAP TRUE
J 0
(4000 3575);
DISPLAY 0.872340 (4000 3575);
DISPLAY INVISIBLE (4000 3575);
FORCEPROP 1 LAST PATH I232
J 0
(3673 3700);
DISPLAY 0.872340 (3673 3700);
PAINT GREEN (3673 3700);
DISPLAY INVISIBLE (3673 3700);
FORCEADD TAP..1
(3675 3900);
FORCEPROP 3 LASTPIN (3625 3900) SIG_NAME P5E_CPU1_G1_TX_C_DN<12>
J 0
(3635 3910);
DISPLAY 0.659574 (3635 3910);
PAINT MONO (3635 3910);
DISPLAY INVISIBLE (3635 3910);
FORCEPROP 1 LASTPIN (3625 3900) BN 12
J 0
(3613 3908);
DISPLAY 0.680851 (3613 3908);
PAINT GREEN (3613 3908);
FORCEPROP 2 LAST CDS_LIB standard
J 0
(3675 3900);
DISPLAY INVISIBLE (3675 3900);
FORCEPROP 1 LAST BODY_TYPE PLUMBING
J 0
(3675 3950);
DISPLAY 0.872340 (3675 3950);
PAINT GREEN (3675 3950);
DISPLAY INVISIBLE (3675 3950);
FORCEPROP 1 LAST HDL_TAP TRUE
J 0
(4000 3775);
DISPLAY 0.872340 (4000 3775);
DISPLAY INVISIBLE (4000 3775);
FORCEPROP 1 LAST PATH I233
J 0
(3673 3900);
DISPLAY 0.872340 (3673 3900);
PAINT GREEN (3673 3900);
DISPLAY INVISIBLE (3673 3900);
FORCEADD TAP..1
(3875 3650);
FORCEPROP 3 LASTPIN (3825 3650) SIG_NAME P5E_CPU1_G1_TX_C_DP<11>
J 0
(3835 3660);
DISPLAY 0.659574 (3835 3660);
PAINT MONO (3835 3660);
DISPLAY INVISIBLE (3835 3660);
FORCEPROP 1 LASTPIN (3825 3650) BN 11
J 0
(3813 3658);
DISPLAY 0.680851 (3813 3658);
PAINT GREEN (3813 3658);
FORCEPROP 2 LAST CDS_LIB standard
J 0
(3875 3650);
DISPLAY INVISIBLE (3875 3650);
FORCEPROP 1 LAST BODY_TYPE PLUMBING
J 0
(3875 3700);
DISPLAY 0.872340 (3875 3700);
PAINT GREEN (3875 3700);
DISPLAY INVISIBLE (3875 3700);
FORCEPROP 1 LAST HDL_TAP TRUE
J 0
(4200 3525);
DISPLAY 0.872340 (4200 3525);
DISPLAY INVISIBLE (4200 3525);
FORCEPROP 1 LAST PATH I234
J 0
(3873 3650);
DISPLAY 0.872340 (3873 3650);
PAINT GREEN (3873 3650);
DISPLAY INVISIBLE (3873 3650);
FORCEADD TAP..1
(3875 3850);
FORCEPROP 3 LASTPIN (3825 3850) SIG_NAME P5E_CPU1_G1_TX_C_DP<12>
J 0
(3835 3860);
DISPLAY 0.659574 (3835 3860);
PAINT MONO (3835 3860);
DISPLAY INVISIBLE (3835 3860);
FORCEPROP 1 LASTPIN (3825 3850) BN 12
J 0
(3813 3858);
DISPLAY 0.680851 (3813 3858);
PAINT GREEN (3813 3858);
FORCEPROP 2 LAST CDS_LIB standard
J 0
(3875 3850);
DISPLAY INVISIBLE (3875 3850);
FORCEPROP 1 LAST BODY_TYPE PLUMBING
J 0
(3875 3900);
DISPLAY 0.872340 (3875 3900);
PAINT GREEN (3875 3900);
DISPLAY INVISIBLE (3875 3900);
FORCEPROP 1 LAST HDL_TAP TRUE
J 0
(4200 3725);
DISPLAY 0.872340 (4200 3725);
DISPLAY INVISIBLE (4200 3725);
FORCEPROP 1 LAST PATH I235
J 0
(3873 3850);
DISPLAY 0.872340 (3873 3850);
PAINT GREEN (3873 3850);
DISPLAY INVISIBLE (3873 3850);
FORCEADD Q_CAP_DIFFBUS..2
R 2
(3125 4050);
FORCEPROP 1 LAST LOCATION C683
J 2
(3359 4067);
DISPLAY 0.723404 (3359 4067);
PAINT GREEN (3359 4067);
FORCEPROP 2 LAST $SEC 1
J 2
(3300 4125);
DISPLAY 0.680851 (3300 4125);
PAINT MONO (3300 4125);
DISPLAY INVISIBLE (3300 4125);
FORCEPROP 2 LAST CDS_SEC 1
J 2
(3300 4125);
DISPLAY 0.680851 (3300 4125);
DISPLAY INVISIBLE (3300 4125);
FORCEPROP 2 LASTPIN (3200 4050) $PN 1
J 0
(3210 4060);
DISPLAY 0.808511 (3210 4060);
FORCEPROP 2 LASTPIN (3050 4050) $PN 2
J 2
(3040 4060);
DISPLAY 0.808511 (3040 4060);
FORCEPROP 2 LAST VALUE DIFF BUS_0.22UF
J 2
(2975 4050);
DISPLAY 0.553191 (2975 4050);
FORCEPROP 1 LAST CDS_LMAN_SYM_OUTLINE -25,50,25,-50
J 2
(3125 4050);
DISPLAY 0.468085 (3125 4050);
PAINT GREEN (3125 4050);
DISPLAY INVISIBLE (3125 4050);
FORCEPROP 2 LAST CDS_LIB pure_quanta
J 2
(3125 4050);
DISPLAY INVISIBLE (3125 4050);
FORCEPROP 1 LAST PIN_NAMES_ROTATE TRUE
J 2
(3125 4050);
DISPLAY 0.489362 (3125 4050);
PAINT GREEN (3125 4050);
DISPLAY INVISIBLE (3125 4050);
FORCEPROP 2 LAST VOLTAGE 6.3V
J 2
(2775 4100);
DISPLAY 0.553191 (2775 4100);
DISPLAY INVISIBLE (2775 4100);
FORCEPROP 1 LAST MATERIAL X6S
J 2
(3134 4129);
DISPLAY 0.574468 (3134 4129);
PAINT GREEN (3134 4129);
DISPLAY INVISIBLE (3134 4129);
FORCEPROP 2 LAST PACK_TYPE C0201
J 2
(2950 4100);
DISPLAY 0.553191 (2950 4100);
DISPLAY INVISIBLE (2950 4100);
FORCEPROP 2 LAST TOLERANCE 20%
J 2
(3050 4100);
DISPLAY 0.553191 (3050 4100);
DISPLAY INVISIBLE (3050 4100);
FORCEPROP 1 LAST PART_NUMBER SP_CH4221MEE01
J 2
(3009 4138);
DISPLAY 0.574468 (3009 4138);
PAINT GREEN (3009 4138);
DISPLAY INVISIBLE (3009 4138);
FORCEPROP 1 LAST LOCATION C683
J 0
(3375 4125);
DISPLAY 1.021277 (3375 4125);
DISPLAY INVISIBLE (3375 4125);
FORCEPROP 1 LAST PATH I236
J 2
(3125 4050);
DISPLAY 0.723404 (3125 4050);
DISPLAY INVISIBLE (3125 4050);
FORCEADD OFFPAGE..2
(250 4475);
FORCEPROP 2 LAST $XR0 350 
J 0
(439 4475);
DISPLAY 0.638298 (439 4475);
PAINT MONO (439 4475);
FORCEPROP 2 LAST CDS_LIB standard
J 0
(250 4475);
DISPLAY INVISIBLE (250 4475);
FORCEPROP 1 LAST OFFPAGE TRUE
J 0
(575 4350);
DISPLAY 0.872340 (575 4350);
DISPLAY INVISIBLE (575 4350);
FORCEPROP 1 LAST COMMENT_BODY TRUE
J 0
(205 4380);
DISPLAY 0.872340 (205 4380);
PAINT GREEN (205 4380);
DISPLAY INVISIBLE (205 4380);
FORCEPROP 2 LAST PATH I237
J 0
(450 4525);
DISPLAY 0.680851 (450 4525);
DISPLAY INVISIBLE (450 4525);
FORCEADD OFFPAGE..2
(250 4525);
FORCEPROP 2 LAST $XR0 350 
J 0
(439 4525);
DISPLAY 0.638298 (439 4525);
PAINT MONO (439 4525);
FORCEPROP 2 LAST CDS_LIB standard
J 0
(250 4525);
DISPLAY INVISIBLE (250 4525);
FORCEPROP 1 LAST OFFPAGE TRUE
J 0
(575 4400);
DISPLAY 0.872340 (575 4400);
DISPLAY INVISIBLE (575 4400);
FORCEPROP 1 LAST COMMENT_BODY TRUE
J 0
(205 4430);
DISPLAY 0.872340 (205 4430);
PAINT GREEN (205 4430);
DISPLAY INVISIBLE (205 4430);
FORCEPROP 2 LAST PATH I238
J 0
(450 4575);
DISPLAY 0.680851 (450 4575);
DISPLAY INVISIBLE (450 4575);
FORCEADD OFFPAGE..1
(1200 4475);
FORCEPROP 2 LAST $XR0 49 
J 0
(949 4475);
DISPLAY 0.638298 (949 4475);
PAINT MONO (949 4475);
FORCEPROP 2 LAST CDS_LIB standard
J 0
(1200 4475);
DISPLAY INVISIBLE (1200 4475);
FORCEPROP 1 LAST OFFPAGE TRUE
J 0
(1525 4350);
DISPLAY 0.872340 (1525 4350);
DISPLAY INVISIBLE (1525 4350);
FORCEPROP 1 LAST COMMENT_BODY TRUE
J 0
(1325 4375);
DISPLAY 0.872340 (1325 4375);
PAINT GREEN (1325 4375);
DISPLAY INVISIBLE (1325 4375);
FORCEPROP 2 LAST PATH I239
J 0
(1000 4525);
DISPLAY 0.680851 (1000 4525);
DISPLAY INVISIBLE (1000 4525);
FORCEADD TAP..1
R 2
(-2500 1625);
FORCEPROP 3 LASTPIN (-2450 1625) SIG_NAME P5E_CPU1_P3_TX_DP<1>
J 0
(-2440 1635);
DISPLAY 0.659574 (-2440 1635);
PAINT MONO (-2440 1635);
DISPLAY INVISIBLE (-2440 1635);
FORCEPROP 1 LASTPIN (-2450 1625) BN 1
J 2
(-2438 1633);
DISPLAY 0.680851 (-2438 1633);
PAINT GREEN (-2438 1633);
FORCEPROP 2 LAST CDS_LIB standard
J 0
(-2500 1625);
DISPLAY INVISIBLE (-2500 1625);
FORCEPROP 1 LAST BODY_TYPE PLUMBING
J 2
(-2500 1675);
DISPLAY 0.872340 (-2500 1675);
PAINT GREEN (-2500 1675);
DISPLAY INVISIBLE (-2500 1675);
FORCEPROP 1 LAST HDL_TAP TRUE
J 2
(-2825 1500);
DISPLAY 0.872340 (-2825 1500);
DISPLAY INVISIBLE (-2825 1500);
FORCEPROP 1 LAST PATH I24
J 2
(-2498 1625);
DISPLAY 0.872340 (-2498 1625);
PAINT GREEN (-2498 1625);
DISPLAY INVISIBLE (-2498 1625);
FORCEADD OFFPAGE..1
(1200 4525);
FORCEPROP 2 LAST $XR0 49 
J 0
(949 4525);
DISPLAY 0.638298 (949 4525);
PAINT MONO (949 4525);
FORCEPROP 2 LAST CDS_LIB standard
J 0
(1200 4525);
DISPLAY INVISIBLE (1200 4525);
FORCEPROP 1 LAST OFFPAGE TRUE
J 0
(1525 4400);
DISPLAY 0.872340 (1525 4400);
DISPLAY INVISIBLE (1525 4400);
FORCEPROP 1 LAST COMMENT_BODY TRUE
J 0
(1325 4425);
DISPLAY 0.872340 (1325 4425);
PAINT GREEN (1325 4425);
DISPLAY INVISIBLE (1325 4425);
FORCEPROP 2 LAST PATH I240
J 0
(1000 4575);
DISPLAY 0.680851 (1000 4575);
DISPLAY INVISIBLE (1000 4575);
FORCEADD TAP..1
R 2
(2150 4250);
FORCEPROP 3 LASTPIN (2200 4250) SIG_NAME P5E_CPU1_G1_TX_DP<14>
J 0
(2210 4260);
DISPLAY 0.659574 (2210 4260);
PAINT MONO (2210 4260);
DISPLAY INVISIBLE (2210 4260);
FORCEPROP 1 LASTPIN (2200 4250) BN 14
J 2
(2212 4258);
DISPLAY 0.680851 (2212 4258);
PAINT GREEN (2212 4258);
FORCEPROP 2 LAST CDS_LIB standard
J 0
(2150 4250);
DISPLAY INVISIBLE (2150 4250);
FORCEPROP 1 LAST BODY_TYPE PLUMBING
J 2
(2150 4300);
DISPLAY 0.872340 (2150 4300);
PAINT GREEN (2150 4300);
DISPLAY INVISIBLE (2150 4300);
FORCEPROP 1 LAST HDL_TAP TRUE
J 2
(1825 4125);
DISPLAY 0.872340 (1825 4125);
DISPLAY INVISIBLE (1825 4125);
FORCEPROP 1 LAST PATH I241
J 2
(2152 4250);
DISPLAY 0.872340 (2152 4250);
PAINT GREEN (2152 4250);
DISPLAY INVISIBLE (2152 4250);
FORCEADD TAP..1
R 2
(2150 4050);
FORCEPROP 3 LASTPIN (2200 4050) SIG_NAME P5E_CPU1_G1_TX_DP<13>
J 0
(2210 4060);
DISPLAY 0.659574 (2210 4060);
PAINT MONO (2210 4060);
DISPLAY INVISIBLE (2210 4060);
FORCEPROP 1 LASTPIN (2200 4050) BN 13
J 2
(2212 4058);
DISPLAY 0.680851 (2212 4058);
PAINT GREEN (2212 4058);
FORCEPROP 2 LAST CDS_LIB standard
J 0
(2150 4050);
DISPLAY INVISIBLE (2150 4050);
FORCEPROP 1 LAST BODY_TYPE PLUMBING
J 2
(2150 4100);
DISPLAY 0.872340 (2150 4100);
PAINT GREEN (2150 4100);
DISPLAY INVISIBLE (2150 4100);
FORCEPROP 1 LAST HDL_TAP TRUE
J 2
(1825 3925);
DISPLAY 0.872340 (1825 3925);
DISPLAY INVISIBLE (1825 3925);
FORCEPROP 1 LAST PATH I242
J 2
(2152 4050);
DISPLAY 0.872340 (2152 4050);
PAINT GREEN (2152 4050);
DISPLAY INVISIBLE (2152 4050);
FORCEADD TAP..1
R 2
(2150 4450);
FORCEPROP 3 LASTPIN (2200 4450) SIG_NAME P5E_CPU1_G1_TX_DP<15>
J 0
(2210 4460);
DISPLAY 0.659574 (2210 4460);
PAINT MONO (2210 4460);
DISPLAY INVISIBLE (2210 4460);
FORCEPROP 1 LASTPIN (2200 4450) BN 15
J 2
(2212 4458);
DISPLAY 0.680851 (2212 4458);
PAINT GREEN (2212 4458);
FORCEPROP 2 LAST CDS_LIB standard
J 0
(2150 4450);
DISPLAY INVISIBLE (2150 4450);
FORCEPROP 1 LAST BODY_TYPE PLUMBING
J 2
(2150 4500);
DISPLAY 0.872340 (2150 4500);
PAINT GREEN (2150 4500);
DISPLAY INVISIBLE (2150 4500);
FORCEPROP 1 LAST HDL_TAP TRUE
J 2
(1825 4325);
DISPLAY 0.872340 (1825 4325);
DISPLAY INVISIBLE (1825 4325);
FORCEPROP 1 LAST PATH I243
J 2
(2152 4450);
DISPLAY 0.872340 (2152 4450);
PAINT GREEN (2152 4450);
DISPLAY INVISIBLE (2152 4450);
FORCEADD TAP..1
R 2
(2400 4100);
FORCEPROP 3 LASTPIN (2450 4100) SIG_NAME P5E_CPU1_G1_TX_DN<13>
J 0
(2460 4110);
DISPLAY 0.659574 (2460 4110);
PAINT MONO (2460 4110);
DISPLAY INVISIBLE (2460 4110);
FORCEPROP 1 LASTPIN (2450 4100) BN 13
J 2
(2462 4108);
DISPLAY 0.680851 (2462 4108);
PAINT GREEN (2462 4108);
FORCEPROP 2 LAST CDS_LIB standard
J 0
(2400 4100);
DISPLAY INVISIBLE (2400 4100);
FORCEPROP 1 LAST BODY_TYPE PLUMBING
J 2
(2400 4150);
DISPLAY 0.872340 (2400 4150);
PAINT GREEN (2400 4150);
DISPLAY INVISIBLE (2400 4150);
FORCEPROP 1 LAST HDL_TAP TRUE
J 2
(2075 3975);
DISPLAY 0.872340 (2075 3975);
DISPLAY INVISIBLE (2075 3975);
FORCEPROP 1 LAST PATH I244
J 2
(2402 4100);
DISPLAY 0.872340 (2402 4100);
PAINT GREEN (2402 4100);
DISPLAY INVISIBLE (2402 4100);
FORCEADD TAP..1
R 2
(2400 4500);
FORCEPROP 3 LASTPIN (2450 4500) SIG_NAME P5E_CPU1_G1_TX_DN<15>
J 0
(2460 4510);
DISPLAY 0.659574 (2460 4510);
PAINT MONO (2460 4510);
DISPLAY INVISIBLE (2460 4510);
FORCEPROP 1 LASTPIN (2450 4500) BN 15
J 2
(2462 4508);
DISPLAY 0.680851 (2462 4508);
PAINT GREEN (2462 4508);
FORCEPROP 2 LAST CDS_LIB standard
J 0
(2400 4500);
DISPLAY INVISIBLE (2400 4500);
FORCEPROP 1 LAST BODY_TYPE PLUMBING
J 2
(2400 4550);
DISPLAY 0.872340 (2400 4550);
PAINT GREEN (2400 4550);
DISPLAY INVISIBLE (2400 4550);
FORCEPROP 1 LAST HDL_TAP TRUE
J 2
(2075 4375);
DISPLAY 0.872340 (2075 4375);
DISPLAY INVISIBLE (2075 4375);
FORCEPROP 1 LAST PATH I245
J 2
(2402 4500);
DISPLAY 0.872340 (2402 4500);
PAINT GREEN (2402 4500);
DISPLAY INVISIBLE (2402 4500);
FORCEADD TAP..1
R 2
(2400 4300);
FORCEPROP 3 LASTPIN (2450 4300) SIG_NAME P5E_CPU1_G1_TX_DN<14>
J 0
(2460 4310);
DISPLAY 0.659574 (2460 4310);
PAINT MONO (2460 4310);
DISPLAY INVISIBLE (2460 4310);
FORCEPROP 1 LASTPIN (2450 4300) BN 14
J 2
(2462 4308);
DISPLAY 0.680851 (2462 4308);
PAINT GREEN (2462 4308);
FORCEPROP 2 LAST CDS_LIB standard
J 0
(2400 4300);
DISPLAY INVISIBLE (2400 4300);
FORCEPROP 1 LAST BODY_TYPE PLUMBING
J 2
(2400 4350);
DISPLAY 0.872340 (2400 4350);
PAINT GREEN (2400 4350);
DISPLAY INVISIBLE (2400 4350);
FORCEPROP 1 LAST HDL_TAP TRUE
J 2
(2075 4175);
DISPLAY 0.872340 (2075 4175);
DISPLAY INVISIBLE (2075 4175);
FORCEPROP 1 LAST PATH I246
J 2
(2402 4300);
DISPLAY 0.872340 (2402 4300);
PAINT GREEN (2402 4300);
DISPLAY INVISIBLE (2402 4300);
FORCEADD Q_CAP_DIFFBUS..2
R 2
(3125 4100);
FORCEPROP 1 LAST LOCATION C682
J 2
(3359 4117);
DISPLAY 0.723404 (3359 4117);
PAINT GREEN (3359 4117);
FORCEPROP 2 LAST $SEC 1
J 2
(3300 4175);
DISPLAY 0.680851 (3300 4175);
PAINT MONO (3300 4175);
DISPLAY INVISIBLE (3300 4175);
FORCEPROP 2 LAST CDS_SEC 1
J 2
(3300 4175);
DISPLAY 0.680851 (3300 4175);
DISPLAY INVISIBLE (3300 4175);
FORCEPROP 2 LASTPIN (3200 4100) $PN 1
J 0
(3210 4110);
DISPLAY 0.808511 (3210 4110);
FORCEPROP 2 LASTPIN (3050 4100) $PN 2
J 2
(3040 4110);
DISPLAY 0.808511 (3040 4110);
FORCEPROP 2 LAST VALUE DIFF BUS_0.22UF
J 2
(2975 4100);
DISPLAY 0.553191 (2975 4100);
FORCEPROP 1 LAST CDS_LMAN_SYM_OUTLINE -25,50,25,-50
J 2
(3125 4100);
DISPLAY 0.468085 (3125 4100);
PAINT GREEN (3125 4100);
DISPLAY INVISIBLE (3125 4100);
FORCEPROP 2 LAST CDS_LIB pure_quanta
J 2
(3125 4100);
DISPLAY INVISIBLE (3125 4100);
FORCEPROP 1 LAST PIN_NAMES_ROTATE TRUE
J 2
(3125 4100);
DISPLAY 0.489362 (3125 4100);
PAINT GREEN (3125 4100);
DISPLAY INVISIBLE (3125 4100);
FORCEPROP 2 LAST VOLTAGE 6.3V
J 2
(2775 4150);
DISPLAY 0.553191 (2775 4150);
DISPLAY INVISIBLE (2775 4150);
FORCEPROP 1 LAST MATERIAL X6S
J 2
(3134 4179);
DISPLAY 0.574468 (3134 4179);
PAINT GREEN (3134 4179);
DISPLAY INVISIBLE (3134 4179);
FORCEPROP 2 LAST PACK_TYPE C0201
J 2
(2950 4150);
DISPLAY 0.553191 (2950 4150);
DISPLAY INVISIBLE (2950 4150);
FORCEPROP 2 LAST TOLERANCE 20%
J 2
(3050 4150);
DISPLAY 0.553191 (3050 4150);
DISPLAY INVISIBLE (3050 4150);
FORCEPROP 1 LAST PART_NUMBER SP_CH4221MEE01
J 2
(3009 4188);
DISPLAY 0.574468 (3009 4188);
PAINT GREEN (3009 4188);
DISPLAY INVISIBLE (3009 4188);
FORCEPROP 1 LAST LOCATION C682
J 0
(3375 4175);
DISPLAY 1.021277 (3375 4175);
DISPLAY INVISIBLE (3375 4175);
FORCEPROP 1 LAST PATH I247
J 2
(3125 4100);
DISPLAY 0.723404 (3125 4100);
DISPLAY INVISIBLE (3125 4100);
FORCEADD Q_CAP_DIFFBUS..2
R 2
(3125 4250);
FORCEPROP 1 LAST LOCATION C681
J 2
(3359 4267);
DISPLAY 0.723404 (3359 4267);
PAINT GREEN (3359 4267);
FORCEPROP 2 LAST $SEC 1
J 2
(3300 4325);
DISPLAY 0.680851 (3300 4325);
PAINT MONO (3300 4325);
DISPLAY INVISIBLE (3300 4325);
FORCEPROP 2 LAST CDS_SEC 1
J 2
(3300 4325);
DISPLAY 0.680851 (3300 4325);
DISPLAY INVISIBLE (3300 4325);
FORCEPROP 2 LASTPIN (3200 4250) $PN 1
J 0
(3210 4260);
DISPLAY 0.808511 (3210 4260);
FORCEPROP 2 LASTPIN (3050 4250) $PN 2
J 2
(3040 4260);
DISPLAY 0.808511 (3040 4260);
FORCEPROP 2 LAST VALUE DIFF BUS_0.22UF
J 2
(2975 4250);
DISPLAY 0.553191 (2975 4250);
FORCEPROP 1 LAST CDS_LMAN_SYM_OUTLINE -25,50,25,-50
J 2
(3125 4250);
DISPLAY 0.468085 (3125 4250);
PAINT GREEN (3125 4250);
DISPLAY INVISIBLE (3125 4250);
FORCEPROP 2 LAST CDS_LIB pure_quanta
J 2
(3125 4250);
DISPLAY INVISIBLE (3125 4250);
FORCEPROP 1 LAST PIN_NAMES_ROTATE TRUE
J 2
(3125 4250);
DISPLAY 0.489362 (3125 4250);
PAINT GREEN (3125 4250);
DISPLAY INVISIBLE (3125 4250);
FORCEPROP 2 LAST VOLTAGE 6.3V
J 2
(2775 4300);
DISPLAY 0.553191 (2775 4300);
DISPLAY INVISIBLE (2775 4300);
FORCEPROP 1 LAST MATERIAL X6S
J 2
(3134 4329);
DISPLAY 0.574468 (3134 4329);
PAINT GREEN (3134 4329);
DISPLAY INVISIBLE (3134 4329);
FORCEPROP 2 LAST PACK_TYPE C0201
J 2
(2950 4300);
DISPLAY 0.553191 (2950 4300);
DISPLAY INVISIBLE (2950 4300);
FORCEPROP 2 LAST TOLERANCE 20%
J 2
(3050 4300);
DISPLAY 0.553191 (3050 4300);
DISPLAY INVISIBLE (3050 4300);
FORCEPROP 1 LAST PART_NUMBER SP_CH4221MEE01
J 2
(3009 4338);
DISPLAY 0.574468 (3009 4338);
PAINT GREEN (3009 4338);
DISPLAY INVISIBLE (3009 4338);
FORCEPROP 1 LAST LOCATION C681
J 0
(3375 4325);
DISPLAY 1.021277 (3375 4325);
DISPLAY INVISIBLE (3375 4325);
FORCEPROP 1 LAST PATH I248
J 2
(3125 4250);
DISPLAY 0.723404 (3125 4250);
DISPLAY INVISIBLE (3125 4250);
FORCEADD Q_CAP_DIFFBUS..2
R 2
(3125 4300);
FORCEPROP 1 LAST LOCATION C680
J 2
(3359 4317);
DISPLAY 0.723404 (3359 4317);
PAINT GREEN (3359 4317);
FORCEPROP 2 LAST $SEC 1
J 2
(3300 4375);
DISPLAY 0.680851 (3300 4375);
PAINT MONO (3300 4375);
DISPLAY INVISIBLE (3300 4375);
FORCEPROP 2 LAST CDS_SEC 1
J 2
(3300 4375);
DISPLAY 0.680851 (3300 4375);
DISPLAY INVISIBLE (3300 4375);
FORCEPROP 2 LASTPIN (3200 4300) $PN 1
J 0
(3210 4310);
DISPLAY 0.808511 (3210 4310);
FORCEPROP 2 LASTPIN (3050 4300) $PN 2
J 2
(3040 4310);
DISPLAY 0.808511 (3040 4310);
FORCEPROP 2 LAST VALUE DIFF BUS_0.22UF
J 2
(2975 4300);
DISPLAY 0.553191 (2975 4300);
FORCEPROP 1 LAST CDS_LMAN_SYM_OUTLINE -25,50,25,-50
J 2
(3125 4300);
DISPLAY 0.468085 (3125 4300);
PAINT GREEN (3125 4300);
DISPLAY INVISIBLE (3125 4300);
FORCEPROP 2 LAST CDS_LIB pure_quanta
J 2
(3125 4300);
DISPLAY INVISIBLE (3125 4300);
FORCEPROP 1 LAST PIN_NAMES_ROTATE TRUE
J 2
(3125 4300);
DISPLAY 0.489362 (3125 4300);
PAINT GREEN (3125 4300);
DISPLAY INVISIBLE (3125 4300);
FORCEPROP 2 LAST VOLTAGE 6.3V
J 2
(2775 4350);
DISPLAY 0.553191 (2775 4350);
DISPLAY INVISIBLE (2775 4350);
FORCEPROP 1 LAST MATERIAL X6S
J 2
(3134 4379);
DISPLAY 0.574468 (3134 4379);
PAINT GREEN (3134 4379);
DISPLAY INVISIBLE (3134 4379);
FORCEPROP 2 LAST PACK_TYPE C0201
J 2
(2950 4350);
DISPLAY 0.553191 (2950 4350);
DISPLAY INVISIBLE (2950 4350);
FORCEPROP 2 LAST TOLERANCE 20%
J 2
(3050 4350);
DISPLAY 0.553191 (3050 4350);
DISPLAY INVISIBLE (3050 4350);
FORCEPROP 1 LAST PART_NUMBER SP_CH4221MEE01
J 2
(3009 4388);
DISPLAY 0.574468 (3009 4388);
PAINT GREEN (3009 4388);
DISPLAY INVISIBLE (3009 4388);
FORCEPROP 1 LAST LOCATION C680
J 0
(3375 4375);
DISPLAY 1.021277 (3375 4375);
DISPLAY INVISIBLE (3375 4375);
FORCEPROP 1 LAST PATH I249
J 2
(3125 4300);
DISPLAY 0.723404 (3125 4300);
DISPLAY INVISIBLE (3125 4300);
FORCEADD TAP..1
R 2
(-2500 1825);
FORCEPROP 3 LASTPIN (-2450 1825) SIG_NAME P5E_CPU1_P3_TX_DP<2>
J 0
(-2440 1835);
DISPLAY 0.659574 (-2440 1835);
PAINT MONO (-2440 1835);
DISPLAY INVISIBLE (-2440 1835);
FORCEPROP 1 LASTPIN (-2450 1825) BN 2
J 2
(-2438 1833);
DISPLAY 0.680851 (-2438 1833);
PAINT GREEN (-2438 1833);
FORCEPROP 2 LAST CDS_LIB standard
J 0
(-2500 1825);
DISPLAY INVISIBLE (-2500 1825);
FORCEPROP 1 LAST BODY_TYPE PLUMBING
J 2
(-2500 1875);
DISPLAY 0.872340 (-2500 1875);
PAINT GREEN (-2500 1875);
DISPLAY INVISIBLE (-2500 1875);
FORCEPROP 1 LAST HDL_TAP TRUE
J 2
(-2825 1700);
DISPLAY 0.872340 (-2825 1700);
DISPLAY INVISIBLE (-2825 1700);
FORCEPROP 1 LAST PATH I25
J 2
(-2498 1825);
DISPLAY 0.872340 (-2498 1825);
PAINT GREEN (-2498 1825);
DISPLAY INVISIBLE (-2498 1825);
FORCEADD Q_CAP_DIFFBUS..2
R 2
(3125 4450);
FORCEPROP 1 LAST LOCATION C679
J 2
(3359 4467);
DISPLAY 0.723404 (3359 4467);
PAINT GREEN (3359 4467);
FORCEPROP 2 LAST $SEC 1
J 2
(3300 4525);
DISPLAY 0.680851 (3300 4525);
PAINT MONO (3300 4525);
DISPLAY INVISIBLE (3300 4525);
FORCEPROP 2 LAST CDS_SEC 1
J 2
(3300 4525);
DISPLAY 0.680851 (3300 4525);
DISPLAY INVISIBLE (3300 4525);
FORCEPROP 2 LASTPIN (3200 4450) $PN 1
J 0
(3210 4460);
DISPLAY 0.808511 (3210 4460);
FORCEPROP 2 LASTPIN (3050 4450) $PN 2
J 2
(3040 4460);
DISPLAY 0.808511 (3040 4460);
FORCEPROP 2 LAST VALUE DIFF BUS_0.22UF
J 2
(2975 4450);
DISPLAY 0.553191 (2975 4450);
FORCEPROP 1 LAST CDS_LMAN_SYM_OUTLINE -25,50,25,-50
J 2
(3125 4450);
DISPLAY 0.468085 (3125 4450);
PAINT GREEN (3125 4450);
DISPLAY INVISIBLE (3125 4450);
FORCEPROP 2 LAST CDS_LIB pure_quanta
J 2
(3125 4450);
DISPLAY INVISIBLE (3125 4450);
FORCEPROP 1 LAST PIN_NAMES_ROTATE TRUE
J 2
(3125 4450);
DISPLAY 0.489362 (3125 4450);
PAINT GREEN (3125 4450);
DISPLAY INVISIBLE (3125 4450);
FORCEPROP 2 LAST VOLTAGE 6.3V
J 2
(2775 4500);
DISPLAY 0.553191 (2775 4500);
DISPLAY INVISIBLE (2775 4500);
FORCEPROP 1 LAST MATERIAL X6S
J 2
(3134 4529);
DISPLAY 0.574468 (3134 4529);
PAINT GREEN (3134 4529);
DISPLAY INVISIBLE (3134 4529);
FORCEPROP 2 LAST PACK_TYPE C0201
J 2
(2950 4500);
DISPLAY 0.553191 (2950 4500);
DISPLAY INVISIBLE (2950 4500);
FORCEPROP 2 LAST TOLERANCE 20%
J 2
(3050 4500);
DISPLAY 0.553191 (3050 4500);
DISPLAY INVISIBLE (3050 4500);
FORCEPROP 1 LAST PART_NUMBER SP_CH4221MEE01
J 2
(3009 4538);
DISPLAY 0.574468 (3009 4538);
PAINT GREEN (3009 4538);
DISPLAY INVISIBLE (3009 4538);
FORCEPROP 1 LAST LOCATION C679
J 0
(3375 4525);
DISPLAY 1.021277 (3375 4525);
DISPLAY INVISIBLE (3375 4525);
FORCEPROP 1 LAST PATH I250
J 2
(3125 4450);
DISPLAY 0.723404 (3125 4450);
DISPLAY INVISIBLE (3125 4450);
FORCEADD Q_CAP_DIFFBUS..2
R 2
(3125 4500);
FORCEPROP 1 LAST LOCATION C678
J 2
(3359 4517);
DISPLAY 0.723404 (3359 4517);
PAINT GREEN (3359 4517);
FORCEPROP 2 LAST $SEC 1
J 2
(3300 4575);
DISPLAY 0.680851 (3300 4575);
PAINT MONO (3300 4575);
DISPLAY INVISIBLE (3300 4575);
FORCEPROP 2 LAST CDS_SEC 1
J 2
(3300 4575);
DISPLAY 0.680851 (3300 4575);
DISPLAY INVISIBLE (3300 4575);
FORCEPROP 2 LASTPIN (3200 4500) $PN 1
J 0
(3210 4510);
DISPLAY 0.808511 (3210 4510);
FORCEPROP 2 LASTPIN (3050 4500) $PN 2
J 2
(3040 4510);
DISPLAY 0.808511 (3040 4510);
FORCEPROP 2 LAST VALUE DIFF BUS_0.22UF
J 2
(2975 4500);
DISPLAY 0.553191 (2975 4500);
FORCEPROP 1 LAST MATERIAL X6S
J 2
(3084 4704);
DISPLAY 0.574468 (3084 4704);
PAINT GREEN (3084 4704);
FORCEPROP 2 LAST PACK_TYPE C0201
J 2
(3125 4650);
DISPLAY 0.553191 (3125 4650);
PAINT GREEN (3125 4650);
FORCEPROP 2 LAST VOLTAGE 6.3V
J 2
(3375 4650);
DISPLAY 0.553191 (3375 4650);
PAINT GREEN (3375 4650);
FORCEPROP 2 LAST TOLERANCE 20%
J 2
(3225 4650);
DISPLAY 0.553191 (3225 4650);
PAINT GREEN (3225 4650);
FORCEPROP 2 LAST CDS_LIB pure_quanta
J 2
(3125 4500);
DISPLAY INVISIBLE (3125 4500);
FORCEPROP 1 LAST CDS_LMAN_SYM_OUTLINE -25,50,25,-50
J 2
(3125 4500);
DISPLAY 0.468085 (3125 4500);
PAINT GREEN (3125 4500);
DISPLAY INVISIBLE (3125 4500);
FORCEPROP 1 LAST PIN_NAMES_ROTATE TRUE
J 2
(3125 4500);
DISPLAY 0.489362 (3125 4500);
PAINT GREEN (3125 4500);
DISPLAY INVISIBLE (3125 4500);
FORCEPROP 1 LAST PART_NUMBER SP_CH4221MEE01
J 2
(3384 4588);
DISPLAY 0.574468 (3384 4588);
PAINT GREEN (3384 4588);
DISPLAY INVISIBLE (3384 4588);
FORCEPROP 1 LAST LOCATION C678
J 0
(3375 4575);
DISPLAY 1.021277 (3375 4575);
DISPLAY INVISIBLE (3375 4575);
FORCEPROP 1 LAST PATH I251
J 2
(3125 4500);
DISPLAY 0.723404 (3125 4500);
DISPLAY INVISIBLE (3125 4500);
FORCEADD TAP..1
(3675 4100);
FORCEPROP 3 LASTPIN (3625 4100) SIG_NAME P5E_CPU1_G1_TX_C_DN<13>
J 0
(3635 4110);
DISPLAY 0.659574 (3635 4110);
PAINT MONO (3635 4110);
DISPLAY INVISIBLE (3635 4110);
FORCEPROP 1 LASTPIN (3625 4100) BN 13
J 0
(3613 4108);
DISPLAY 0.680851 (3613 4108);
PAINT GREEN (3613 4108);
FORCEPROP 2 LAST CDS_LIB standard
J 0
(3675 4100);
DISPLAY INVISIBLE (3675 4100);
FORCEPROP 1 LAST BODY_TYPE PLUMBING
J 0
(3675 4150);
DISPLAY 0.872340 (3675 4150);
PAINT GREEN (3675 4150);
DISPLAY INVISIBLE (3675 4150);
FORCEPROP 1 LAST HDL_TAP TRUE
J 0
(4000 3975);
DISPLAY 0.872340 (4000 3975);
DISPLAY INVISIBLE (4000 3975);
FORCEPROP 1 LAST PATH I252
J 0
(3673 4100);
DISPLAY 0.872340 (3673 4100);
PAINT GREEN (3673 4100);
DISPLAY INVISIBLE (3673 4100);
FORCEADD TAP..1
(3675 4500);
FORCEPROP 3 LASTPIN (3625 4500) SIG_NAME P5E_CPU1_G1_TX_C_DN<15>
J 0
(3635 4510);
DISPLAY 0.659574 (3635 4510);
PAINT MONO (3635 4510);
DISPLAY INVISIBLE (3635 4510);
FORCEPROP 1 LASTPIN (3625 4500) BN 15
J 0
(3613 4508);
DISPLAY 0.680851 (3613 4508);
PAINT GREEN (3613 4508);
FORCEPROP 2 LAST CDS_LIB standard
J 0
(3675 4500);
DISPLAY INVISIBLE (3675 4500);
FORCEPROP 1 LAST BODY_TYPE PLUMBING
J 0
(3675 4550);
DISPLAY 0.872340 (3675 4550);
PAINT GREEN (3675 4550);
DISPLAY INVISIBLE (3675 4550);
FORCEPROP 1 LAST HDL_TAP TRUE
J 0
(4000 4375);
DISPLAY 0.872340 (4000 4375);
DISPLAY INVISIBLE (4000 4375);
FORCEPROP 1 LAST PATH I253
J 0
(3673 4500);
DISPLAY 0.872340 (3673 4500);
PAINT GREEN (3673 4500);
DISPLAY INVISIBLE (3673 4500);
FORCEADD TAP..1
(3675 4300);
FORCEPROP 3 LASTPIN (3625 4300) SIG_NAME P5E_CPU1_G1_TX_C_DN<14>
J 0
(3635 4310);
DISPLAY 0.659574 (3635 4310);
PAINT MONO (3635 4310);
DISPLAY INVISIBLE (3635 4310);
FORCEPROP 1 LASTPIN (3625 4300) BN 14
J 0
(3613 4308);
DISPLAY 0.680851 (3613 4308);
PAINT GREEN (3613 4308);
FORCEPROP 2 LAST CDS_LIB standard
J 0
(3675 4300);
DISPLAY INVISIBLE (3675 4300);
FORCEPROP 1 LAST BODY_TYPE PLUMBING
J 0
(3675 4350);
DISPLAY 0.872340 (3675 4350);
PAINT GREEN (3675 4350);
DISPLAY INVISIBLE (3675 4350);
FORCEPROP 1 LAST HDL_TAP TRUE
J 0
(4000 4175);
DISPLAY 0.872340 (4000 4175);
DISPLAY INVISIBLE (4000 4175);
FORCEPROP 1 LAST PATH I254
J 0
(3673 4300);
DISPLAY 0.872340 (3673 4300);
PAINT GREEN (3673 4300);
DISPLAY INVISIBLE (3673 4300);
FORCEADD TAP..1
(3875 4250);
FORCEPROP 3 LASTPIN (3825 4250) SIG_NAME P5E_CPU1_G1_TX_C_DP<14>
J 0
(3835 4260);
DISPLAY 0.659574 (3835 4260);
PAINT MONO (3835 4260);
DISPLAY INVISIBLE (3835 4260);
FORCEPROP 1 LASTPIN (3825 4250) BN 14
J 0
(3813 4258);
DISPLAY 0.680851 (3813 4258);
PAINT GREEN (3813 4258);
FORCEPROP 2 LAST CDS_LIB standard
J 0
(3875 4250);
DISPLAY INVISIBLE (3875 4250);
FORCEPROP 1 LAST BODY_TYPE PLUMBING
J 0
(3875 4300);
DISPLAY 0.872340 (3875 4300);
PAINT GREEN (3875 4300);
DISPLAY INVISIBLE (3875 4300);
FORCEPROP 1 LAST HDL_TAP TRUE
J 0
(4200 4125);
DISPLAY 0.872340 (4200 4125);
DISPLAY INVISIBLE (4200 4125);
FORCEPROP 1 LAST PATH I255
J 0
(3873 4250);
DISPLAY 0.872340 (3873 4250);
PAINT GREEN (3873 4250);
DISPLAY INVISIBLE (3873 4250);
FORCEADD TAP..1
(3875 4050);
FORCEPROP 3 LASTPIN (3825 4050) SIG_NAME P5E_CPU1_G1_TX_C_DP<13>
J 0
(3835 4060);
DISPLAY 0.659574 (3835 4060);
PAINT MONO (3835 4060);
DISPLAY INVISIBLE (3835 4060);
FORCEPROP 1 LASTPIN (3825 4050) BN 13
J 0
(3813 4058);
DISPLAY 0.680851 (3813 4058);
PAINT GREEN (3813 4058);
FORCEPROP 2 LAST CDS_LIB standard
J 0
(3875 4050);
DISPLAY INVISIBLE (3875 4050);
FORCEPROP 1 LAST BODY_TYPE PLUMBING
J 0
(3875 4100);
DISPLAY 0.872340 (3875 4100);
PAINT GREEN (3875 4100);
DISPLAY INVISIBLE (3875 4100);
FORCEPROP 1 LAST HDL_TAP TRUE
J 0
(4200 3925);
DISPLAY 0.872340 (4200 3925);
DISPLAY INVISIBLE (4200 3925);
FORCEPROP 1 LAST PATH I256
J 0
(3873 4050);
DISPLAY 0.872340 (3873 4050);
PAINT GREEN (3873 4050);
DISPLAY INVISIBLE (3873 4050);
FORCEADD TAP..1
(3875 4450);
FORCEPROP 3 LASTPIN (3825 4450) SIG_NAME P5E_CPU1_G1_TX_C_DP<15>
J 0
(3835 4460);
DISPLAY 0.659574 (3835 4460);
PAINT MONO (3835 4460);
DISPLAY INVISIBLE (3835 4460);
FORCEPROP 1 LASTPIN (3825 4450) BN 15
J 0
(3813 4458);
DISPLAY 0.680851 (3813 4458);
PAINT GREEN (3813 4458);
FORCEPROP 2 LAST CDS_LIB standard
J 0
(3875 4450);
DISPLAY INVISIBLE (3875 4450);
FORCEPROP 1 LAST BODY_TYPE PLUMBING
J 0
(3875 4500);
DISPLAY 0.872340 (3875 4500);
PAINT GREEN (3875 4500);
DISPLAY INVISIBLE (3875 4500);
FORCEPROP 1 LAST HDL_TAP TRUE
J 0
(4200 4325);
DISPLAY 0.872340 (4200 4325);
DISPLAY INVISIBLE (4200 4325);
FORCEPROP 1 LAST PATH I257
J 0
(3873 4450);
DISPLAY 0.872340 (3873 4450);
PAINT GREEN (3873 4450);
DISPLAY INVISIBLE (3873 4450);
FORCEADD OFFPAGE..2
(4900 50);
FORCEPROP 2 LAST $XR0 144 
J 0
(5089 50);
DISPLAY 0.638298 (5089 50);
PAINT MONO (5089 50);
FORCEPROP 2 LAST CDS_LIB standard
J 0
(4900 50);
DISPLAY INVISIBLE (4900 50);
FORCEPROP 1 LAST OFFPAGE TRUE
J 0
(5225 -75);
DISPLAY 0.872340 (5225 -75);
DISPLAY INVISIBLE (5225 -75);
FORCEPROP 1 LAST COMMENT_BODY TRUE
J 0
(4855 -45);
DISPLAY 0.872340 (4855 -45);
PAINT GREEN (4855 -45);
DISPLAY INVISIBLE (4855 -45);
FORCEPROP 2 LAST PATH I258
J 0
(5075 125);
DISPLAY 0.680851 (5075 125);
DISPLAY INVISIBLE (5075 125);
FORCEADD OFFPAGE..2
(4900 0);
FORCEPROP 2 LAST $XR0 144 
J 0
(5089 0);
DISPLAY 0.638298 (5089 0);
PAINT MONO (5089 0);
FORCEPROP 2 LAST CDS_LIB standard
J 0
(4900 0);
DISPLAY INVISIBLE (4900 0);
FORCEPROP 1 LAST OFFPAGE TRUE
J 0
(5225 -125);
DISPLAY 0.872340 (5225 -125);
DISPLAY INVISIBLE (5225 -125);
FORCEPROP 1 LAST COMMENT_BODY TRUE
J 0
(4855 -95);
DISPLAY 0.872340 (4855 -95);
PAINT GREEN (4855 -95);
DISPLAY INVISIBLE (4855 -95);
FORCEPROP 2 LAST PATH I259
J 0
(5075 75);
DISPLAY 0.680851 (5075 75);
DISPLAY INVISIBLE (5075 75);
FORCEADD TAP..1
R 2
(-2250 1675);
FORCEPROP 3 LASTPIN (-2200 1675) SIG_NAME P5E_CPU1_P3_TX_DN<1>
J 0
(-2190 1685);
DISPLAY 0.659574 (-2190 1685);
PAINT MONO (-2190 1685);
DISPLAY INVISIBLE (-2190 1685);
FORCEPROP 1 LASTPIN (-2200 1675) BN 1
J 2
(-2188 1683);
DISPLAY 0.680851 (-2188 1683);
PAINT GREEN (-2188 1683);
FORCEPROP 2 LAST CDS_LIB standard
J 0
(-2250 1675);
DISPLAY INVISIBLE (-2250 1675);
FORCEPROP 1 LAST BODY_TYPE PLUMBING
J 2
(-2250 1725);
DISPLAY 0.872340 (-2250 1725);
PAINT GREEN (-2250 1725);
DISPLAY INVISIBLE (-2250 1725);
FORCEPROP 1 LAST HDL_TAP TRUE
J 2
(-2575 1550);
DISPLAY 0.872340 (-2575 1550);
DISPLAY INVISIBLE (-2575 1550);
FORCEPROP 1 LAST PATH I26
J 2
(-2248 1675);
DISPLAY 0.872340 (-2248 1675);
PAINT GREEN (-2248 1675);
DISPLAY INVISIBLE (-2248 1675);
FORCEADD OFFPAGE..2
(4875 2875);
FORCEPROP 2 LAST $XR0 137 
J 0
(5064 2875);
DISPLAY 0.638298 (5064 2875);
PAINT MONO (5064 2875);
FORCEPROP 2 LAST CDS_LIB standard
J 0
(4875 2875);
DISPLAY INVISIBLE (4875 2875);
FORCEPROP 1 LAST OFFPAGE TRUE
J 0
(5200 2750);
DISPLAY 0.872340 (5200 2750);
DISPLAY INVISIBLE (5200 2750);
FORCEPROP 1 LAST COMMENT_BODY TRUE
J 0
(4830 2780);
DISPLAY 0.872340 (4830 2780);
PAINT GREEN (4830 2780);
DISPLAY INVISIBLE (4830 2780);
FORCEPROP 2 LAST PATH I260
J 0
(5075 2925);
DISPLAY 0.680851 (5075 2925);
DISPLAY INVISIBLE (5075 2925);
FORCEADD OFFPAGE..2
(4875 2925);
FORCEPROP 2 LAST $XR0 137 
J 0
(5064 2925);
DISPLAY 0.638298 (5064 2925);
PAINT MONO (5064 2925);
FORCEPROP 2 LAST CDS_LIB standard
J 0
(4875 2925);
DISPLAY INVISIBLE (4875 2925);
FORCEPROP 1 LAST OFFPAGE TRUE
J 0
(5200 2800);
DISPLAY 0.872340 (5200 2800);
DISPLAY INVISIBLE (5200 2800);
FORCEPROP 1 LAST COMMENT_BODY TRUE
J 0
(4830 2830);
DISPLAY 0.872340 (4830 2830);
PAINT GREEN (4830 2830);
DISPLAY INVISIBLE (4830 2830);
FORCEPROP 2 LAST PATH I261
J 0
(5075 2975);
DISPLAY 0.680851 (5075 2975);
DISPLAY INVISIBLE (5075 2975);
FORCEADD OFFPAGE..2
(4875 4475);
FORCEPROP 2 LAST $XR0 137 
J 0
(5064 4475);
DISPLAY 0.638298 (5064 4475);
PAINT MONO (5064 4475);
FORCEPROP 2 LAST CDS_LIB standard
J 0
(4875 4475);
DISPLAY INVISIBLE (4875 4475);
FORCEPROP 1 LAST OFFPAGE TRUE
J 0
(5200 4350);
DISPLAY 0.872340 (5200 4350);
DISPLAY INVISIBLE (5200 4350);
FORCEPROP 1 LAST COMMENT_BODY TRUE
J 0
(4830 4380);
DISPLAY 0.872340 (4830 4380);
PAINT GREEN (4830 4380);
DISPLAY INVISIBLE (4830 4380);
FORCEPROP 2 LAST PATH I262
J 0
(5075 4525);
DISPLAY 0.680851 (5075 4525);
DISPLAY INVISIBLE (5075 4525);
FORCEADD OFFPAGE..2
(4875 4525);
FORCEPROP 2 LAST $XR0 137 
J 0
(5064 4525);
DISPLAY 0.638298 (5064 4525);
PAINT MONO (5064 4525);
FORCEPROP 2 LAST CDS_LIB standard
J 0
(4875 4525);
DISPLAY INVISIBLE (4875 4525);
FORCEPROP 1 LAST OFFPAGE TRUE
J 0
(5200 4400);
DISPLAY 0.872340 (5200 4400);
DISPLAY INVISIBLE (5200 4400);
FORCEPROP 1 LAST COMMENT_BODY TRUE
J 0
(4830 4430);
DISPLAY 0.872340 (4830 4430);
PAINT GREEN (4830 4430);
DISPLAY INVISIBLE (4830 4430);
FORCEPROP 2 LAST PATH I263
J 0
(5075 4575);
DISPLAY 0.680851 (5075 4575);
DISPLAY INVISIBLE (5075 4575);
FORCEADD TAP..1
(3875 2050);
FORCEPROP 3 LASTPIN (3825 2050) SIG_NAME P5E_CPU1_G1_TX_C_DP<3>
J 0
(3835 2060);
DISPLAY 0.659574 (3835 2060);
PAINT MONO (3835 2060);
DISPLAY INVISIBLE (3835 2060);
FORCEPROP 1 LASTPIN (3825 2050) BN 3
J 0
(3813 2058);
DISPLAY 0.680851 (3813 2058);
PAINT GREEN (3813 2058);
FORCEPROP 2 LAST CDS_LIB standard
J 0
(3875 2050);
DISPLAY INVISIBLE (3875 2050);
FORCEPROP 1 LAST BODY_TYPE PLUMBING
J 0
(3875 2100);
DISPLAY 0.872340 (3875 2100);
PAINT GREEN (3875 2100);
DISPLAY INVISIBLE (3875 2100);
FORCEPROP 1 LAST HDL_TAP TRUE
J 0
(4200 1925);
DISPLAY 0.872340 (4200 1925);
DISPLAY INVISIBLE (4200 1925);
FORCEPROP 1 LAST PATH I264
J 0
(3873 2050);
DISPLAY 0.872340 (3873 2050);
PAINT GREEN (3873 2050);
DISPLAY INVISIBLE (3873 2050);
FORCEADD TAP..1
R 2
(-2250 1475);
FORCEPROP 3 LASTPIN (-2200 1475) SIG_NAME P5E_CPU1_P3_TX_DN<0>
J 0
(-2190 1485);
DISPLAY 0.659574 (-2190 1485);
PAINT MONO (-2190 1485);
DISPLAY INVISIBLE (-2190 1485);
FORCEPROP 1 LASTPIN (-2200 1475) BN 0
J 2
(-2188 1483);
DISPLAY 0.680851 (-2188 1483);
PAINT GREEN (-2188 1483);
FORCEPROP 2 LAST CDS_LIB standard
J 0
(-2250 1475);
DISPLAY INVISIBLE (-2250 1475);
FORCEPROP 1 LAST BODY_TYPE PLUMBING
J 2
(-2250 1525);
DISPLAY 0.872340 (-2250 1525);
PAINT GREEN (-2250 1525);
DISPLAY INVISIBLE (-2250 1525);
FORCEPROP 1 LAST HDL_TAP TRUE
J 2
(-2575 1350);
DISPLAY 0.872340 (-2575 1350);
DISPLAY INVISIBLE (-2575 1350);
FORCEPROP 1 LAST PATH I27
J 2
(-2248 1475);
DISPLAY 0.872340 (-2248 1475);
PAINT GREEN (-2248 1475);
DISPLAY INVISIBLE (-2248 1475);
FORCEADD TAP..1
R 2
(-2250 1875);
FORCEPROP 3 LASTPIN (-2200 1875) SIG_NAME P5E_CPU1_P3_TX_DN<2>
J 0
(-2190 1885);
DISPLAY 0.659574 (-2190 1885);
PAINT MONO (-2190 1885);
DISPLAY INVISIBLE (-2190 1885);
FORCEPROP 1 LASTPIN (-2200 1875) BN 2
J 2
(-2188 1883);
DISPLAY 0.680851 (-2188 1883);
PAINT GREEN (-2188 1883);
FORCEPROP 2 LAST CDS_LIB standard
J 0
(-2250 1875);
DISPLAY INVISIBLE (-2250 1875);
FORCEPROP 1 LAST BODY_TYPE PLUMBING
J 2
(-2250 1925);
DISPLAY 0.872340 (-2250 1925);
PAINT GREEN (-2250 1925);
DISPLAY INVISIBLE (-2250 1925);
FORCEPROP 1 LAST HDL_TAP TRUE
J 2
(-2575 1750);
DISPLAY 0.872340 (-2575 1750);
DISPLAY INVISIBLE (-2575 1750);
FORCEPROP 1 LAST PATH I28
J 2
(-2248 1875);
DISPLAY 0.872340 (-2248 1875);
PAINT GREEN (-2248 1875);
DISPLAY INVISIBLE (-2248 1875);
FORCEADD OFFPAGE..1
(-3450 2900);
FORCEPROP 2 LAST $XR0 52 
J 0
(-3671 2900);
DISPLAY 0.638298 (-3671 2900);
PAINT MONO (-3671 2900);
FORCEPROP 2 LAST CDS_LIB standard
J 0
(-3450 2900);
DISPLAY INVISIBLE (-3450 2900);
FORCEPROP 1 LAST OFFPAGE TRUE
J 0
(-3125 2775);
DISPLAY 0.872340 (-3125 2775);
DISPLAY INVISIBLE (-3125 2775);
FORCEPROP 1 LAST COMMENT_BODY TRUE
J 0
(-3325 2800);
DISPLAY 0.872340 (-3325 2800);
PAINT GREEN (-3325 2800);
DISPLAY INVISIBLE (-3325 2800);
FORCEPROP 2 LAST PATH I29
J 0
(-3700 2950);
DISPLAY 0.680851 (-3700 2950);
DISPLAY INVISIBLE (-3700 2950);
FORCEADD TAP..1
R 2
(-2350 -350);
FORCEPROP 3 LASTPIN (-2300 -350) SIG_NAME P3E_CPU0_P4_TX_DN<2>
J 0
(-2290 -340);
DISPLAY 0.659574 (-2290 -340);
PAINT MONO (-2290 -340);
DISPLAY INVISIBLE (-2290 -340);
FORCEPROP 1 LASTPIN (-2300 -350) BN 2
J 2
(-2288 -342);
DISPLAY 0.680851 (-2288 -342);
PAINT MONO (-2288 -342);
FORCEPROP 2 LAST CDS_LIB standard
J 0
(-2350 -350);
DISPLAY INVISIBLE (-2350 -350);
FORCEPROP 1 LAST BODY_TYPE PLUMBING
J 2
(-2350 -300);
DISPLAY 0.872340 (-2350 -300);
PAINT GREEN (-2350 -300);
DISPLAY INVISIBLE (-2350 -300);
FORCEPROP 1 LAST HDL_TAP TRUE
J 2
(-2675 -475);
DISPLAY 0.872340 (-2675 -475);
DISPLAY INVISIBLE (-2675 -475);
FORCEPROP 1 LAST PATH I3
J 2
(-2348 -350);
DISPLAY 0.872340 (-2348 -350);
PAINT GREEN (-2348 -350);
DISPLAY INVISIBLE (-2348 -350);
FORCEADD OFFPAGE..1
(-3450 2850);
FORCEPROP 2 LAST $XR0 52 
J 0
(-3671 2850);
DISPLAY 0.638298 (-3671 2850);
PAINT MONO (-3671 2850);
FORCEPROP 2 LAST CDS_LIB standard
J 0
(-3450 2850);
DISPLAY INVISIBLE (-3450 2850);
FORCEPROP 1 LAST OFFPAGE TRUE
J 0
(-3125 2725);
DISPLAY 0.872340 (-3125 2725);
DISPLAY INVISIBLE (-3125 2725);
FORCEPROP 1 LAST COMMENT_BODY TRUE
J 0
(-3325 2750);
DISPLAY 0.872340 (-3325 2750);
PAINT GREEN (-3325 2750);
DISPLAY INVISIBLE (-3325 2750);
FORCEPROP 2 LAST PATH I30
J 0
(-3700 2900);
DISPLAY 0.680851 (-3700 2900);
DISPLAY INVISIBLE (-3700 2900);
FORCEADD TAP..1
R 2
(-2500 2025);
FORCEPROP 3 LASTPIN (-2450 2025) SIG_NAME P5E_CPU1_P3_TX_DP<3>
J 0
(-2440 2035);
DISPLAY 0.659574 (-2440 2035);
PAINT MONO (-2440 2035);
DISPLAY INVISIBLE (-2440 2035);
FORCEPROP 1 LASTPIN (-2450 2025) BN 3
J 2
(-2438 2033);
DISPLAY 0.680851 (-2438 2033);
PAINT GREEN (-2438 2033);
FORCEPROP 2 LAST CDS_LIB standard
J 0
(-2500 2025);
DISPLAY INVISIBLE (-2500 2025);
FORCEPROP 1 LAST BODY_TYPE PLUMBING
J 2
(-2500 2075);
DISPLAY 0.872340 (-2500 2075);
PAINT GREEN (-2500 2075);
DISPLAY INVISIBLE (-2500 2075);
FORCEPROP 1 LAST HDL_TAP TRUE
J 2
(-2825 1900);
DISPLAY 0.872340 (-2825 1900);
DISPLAY INVISIBLE (-2825 1900);
FORCEPROP 1 LAST PATH I31
J 2
(-2498 2025);
DISPLAY 0.872340 (-2498 2025);
PAINT GREEN (-2498 2025);
DISPLAY INVISIBLE (-2498 2025);
FORCEADD TAP..1
R 2
(-2500 2225);
FORCEPROP 3 LASTPIN (-2450 2225) SIG_NAME P5E_CPU1_P3_TX_DP<4>
J 0
(-2440 2235);
DISPLAY 0.659574 (-2440 2235);
PAINT MONO (-2440 2235);
DISPLAY INVISIBLE (-2440 2235);
FORCEPROP 1 LASTPIN (-2450 2225) BN 4
J 2
(-2438 2233);
DISPLAY 0.680851 (-2438 2233);
PAINT GREEN (-2438 2233);
FORCEPROP 2 LAST CDS_LIB standard
J 0
(-2500 2225);
DISPLAY INVISIBLE (-2500 2225);
FORCEPROP 1 LAST BODY_TYPE PLUMBING
J 2
(-2500 2275);
DISPLAY 0.872340 (-2500 2275);
PAINT GREEN (-2500 2275);
DISPLAY INVISIBLE (-2500 2275);
FORCEPROP 1 LAST HDL_TAP TRUE
J 2
(-2825 2100);
DISPLAY 0.872340 (-2825 2100);
DISPLAY INVISIBLE (-2825 2100);
FORCEPROP 1 LAST PATH I32
J 2
(-2498 2225);
DISPLAY 0.872340 (-2498 2225);
PAINT GREEN (-2498 2225);
DISPLAY INVISIBLE (-2498 2225);
FORCEADD TAP..1
R 2
(-2500 2425);
FORCEPROP 3 LASTPIN (-2450 2425) SIG_NAME P5E_CPU1_P3_TX_DP<5>
J 0
(-2440 2435);
DISPLAY 0.659574 (-2440 2435);
PAINT MONO (-2440 2435);
DISPLAY INVISIBLE (-2440 2435);
FORCEPROP 1 LASTPIN (-2450 2425) BN 5
J 2
(-2438 2433);
DISPLAY 0.680851 (-2438 2433);
PAINT GREEN (-2438 2433);
FORCEPROP 2 LAST CDS_LIB standard
J 0
(-2500 2425);
DISPLAY INVISIBLE (-2500 2425);
FORCEPROP 1 LAST BODY_TYPE PLUMBING
J 2
(-2500 2475);
DISPLAY 0.872340 (-2500 2475);
PAINT GREEN (-2500 2475);
DISPLAY INVISIBLE (-2500 2475);
FORCEPROP 1 LAST HDL_TAP TRUE
J 2
(-2825 2300);
DISPLAY 0.872340 (-2825 2300);
DISPLAY INVISIBLE (-2825 2300);
FORCEPROP 1 LAST PATH I33
J 2
(-2498 2425);
DISPLAY 0.872340 (-2498 2425);
PAINT GREEN (-2498 2425);
DISPLAY INVISIBLE (-2498 2425);
FORCEADD TAP..1
R 2
(-2250 2075);
FORCEPROP 3 LASTPIN (-2200 2075) SIG_NAME P5E_CPU1_P3_TX_DN<3>
J 0
(-2190 2085);
DISPLAY 0.659574 (-2190 2085);
PAINT MONO (-2190 2085);
DISPLAY INVISIBLE (-2190 2085);
FORCEPROP 1 LASTPIN (-2200 2075) BN 3
J 2
(-2188 2083);
DISPLAY 0.680851 (-2188 2083);
PAINT GREEN (-2188 2083);
FORCEPROP 2 LAST CDS_LIB standard
J 0
(-2250 2075);
DISPLAY INVISIBLE (-2250 2075);
FORCEPROP 1 LAST BODY_TYPE PLUMBING
J 2
(-2250 2125);
DISPLAY 0.872340 (-2250 2125);
PAINT GREEN (-2250 2125);
DISPLAY INVISIBLE (-2250 2125);
FORCEPROP 1 LAST HDL_TAP TRUE
J 2
(-2575 1950);
DISPLAY 0.872340 (-2575 1950);
DISPLAY INVISIBLE (-2575 1950);
FORCEPROP 1 LAST PATH I34
J 2
(-2248 2075);
DISPLAY 0.872340 (-2248 2075);
PAINT GREEN (-2248 2075);
DISPLAY INVISIBLE (-2248 2075);
FORCEADD TAP..1
R 2
(-2250 2275);
FORCEPROP 3 LASTPIN (-2200 2275) SIG_NAME P5E_CPU1_P3_TX_DN<4>
J 0
(-2190 2285);
DISPLAY 0.659574 (-2190 2285);
PAINT MONO (-2190 2285);
DISPLAY INVISIBLE (-2190 2285);
FORCEPROP 1 LASTPIN (-2200 2275) BN 4
J 2
(-2188 2283);
DISPLAY 0.680851 (-2188 2283);
PAINT GREEN (-2188 2283);
FORCEPROP 2 LAST CDS_LIB standard
J 0
(-2250 2275);
DISPLAY INVISIBLE (-2250 2275);
FORCEPROP 1 LAST BODY_TYPE PLUMBING
J 2
(-2250 2325);
DISPLAY 0.872340 (-2250 2325);
PAINT GREEN (-2250 2325);
DISPLAY INVISIBLE (-2250 2325);
FORCEPROP 1 LAST HDL_TAP TRUE
J 2
(-2575 2150);
DISPLAY 0.872340 (-2575 2150);
DISPLAY INVISIBLE (-2575 2150);
FORCEPROP 1 LAST PATH I35
J 2
(-2248 2275);
DISPLAY 0.872340 (-2248 2275);
PAINT GREEN (-2248 2275);
DISPLAY INVISIBLE (-2248 2275);
FORCEADD TAP..1
R 2
(-2250 2475);
FORCEPROP 3 LASTPIN (-2200 2475) SIG_NAME P5E_CPU1_P3_TX_DN<5>
J 0
(-2190 2485);
DISPLAY 0.659574 (-2190 2485);
PAINT MONO (-2190 2485);
DISPLAY INVISIBLE (-2190 2485);
FORCEPROP 1 LASTPIN (-2200 2475) BN 5
J 2
(-2188 2483);
DISPLAY 0.680851 (-2188 2483);
PAINT GREEN (-2188 2483);
FORCEPROP 2 LAST CDS_LIB standard
J 0
(-2250 2475);
DISPLAY INVISIBLE (-2250 2475);
FORCEPROP 1 LAST BODY_TYPE PLUMBING
J 2
(-2250 2525);
DISPLAY 0.872340 (-2250 2525);
PAINT GREEN (-2250 2525);
DISPLAY INVISIBLE (-2250 2525);
FORCEPROP 1 LAST HDL_TAP TRUE
J 2
(-2575 2350);
DISPLAY 0.872340 (-2575 2350);
DISPLAY INVISIBLE (-2575 2350);
FORCEPROP 1 LAST PATH I36
J 2
(-2248 2475);
DISPLAY 0.872340 (-2248 2475);
PAINT GREEN (-2248 2475);
DISPLAY INVISIBLE (-2248 2475);
FORCEADD TAP..1
R 2
(-2500 2625);
FORCEPROP 3 LASTPIN (-2450 2625) SIG_NAME P5E_CPU1_P3_TX_DP<6>
J 0
(-2440 2635);
DISPLAY 0.659574 (-2440 2635);
PAINT MONO (-2440 2635);
DISPLAY INVISIBLE (-2440 2635);
FORCEPROP 1 LASTPIN (-2450 2625) BN 6
J 2
(-2438 2633);
DISPLAY 0.680851 (-2438 2633);
PAINT GREEN (-2438 2633);
FORCEPROP 2 LAST CDS_LIB standard
J 0
(-2500 2625);
DISPLAY INVISIBLE (-2500 2625);
FORCEPROP 1 LAST BODY_TYPE PLUMBING
J 2
(-2500 2675);
DISPLAY 0.872340 (-2500 2675);
PAINT GREEN (-2500 2675);
DISPLAY INVISIBLE (-2500 2675);
FORCEPROP 1 LAST HDL_TAP TRUE
J 2
(-2825 2500);
DISPLAY 0.872340 (-2825 2500);
DISPLAY INVISIBLE (-2825 2500);
FORCEPROP 1 LAST PATH I37
J 2
(-2498 2625);
DISPLAY 0.872340 (-2498 2625);
PAINT GREEN (-2498 2625);
DISPLAY INVISIBLE (-2498 2625);
FORCEADD TAP..1
R 2
(-2500 2825);
FORCEPROP 3 LASTPIN (-2450 2825) SIG_NAME P5E_CPU1_P3_TX_DP<7>
J 0
(-2440 2835);
DISPLAY 0.659574 (-2440 2835);
PAINT MONO (-2440 2835);
DISPLAY INVISIBLE (-2440 2835);
FORCEPROP 1 LASTPIN (-2450 2825) BN 7
J 2
(-2438 2833);
DISPLAY 0.680851 (-2438 2833);
PAINT GREEN (-2438 2833);
FORCEPROP 2 LAST CDS_LIB standard
J 0
(-2500 2825);
DISPLAY INVISIBLE (-2500 2825);
FORCEPROP 1 LAST BODY_TYPE PLUMBING
J 2
(-2500 2875);
DISPLAY 0.872340 (-2500 2875);
PAINT GREEN (-2500 2875);
DISPLAY INVISIBLE (-2500 2875);
FORCEPROP 1 LAST HDL_TAP TRUE
J 2
(-2825 2700);
DISPLAY 0.872340 (-2825 2700);
DISPLAY INVISIBLE (-2825 2700);
FORCEPROP 1 LAST PATH I38
J 2
(-2498 2825);
DISPLAY 0.872340 (-2498 2825);
PAINT GREEN (-2498 2825);
DISPLAY INVISIBLE (-2498 2825);
FORCEADD TAP..1
R 2
(-2250 2675);
FORCEPROP 3 LASTPIN (-2200 2675) SIG_NAME P5E_CPU1_P3_TX_DN<6>
J 0
(-2190 2685);
DISPLAY 0.659574 (-2190 2685);
PAINT MONO (-2190 2685);
DISPLAY INVISIBLE (-2190 2685);
FORCEPROP 1 LASTPIN (-2200 2675) BN 6
J 2
(-2188 2683);
DISPLAY 0.680851 (-2188 2683);
PAINT GREEN (-2188 2683);
FORCEPROP 2 LAST CDS_LIB standard
J 0
(-2250 2675);
DISPLAY INVISIBLE (-2250 2675);
FORCEPROP 1 LAST BODY_TYPE PLUMBING
J 2
(-2250 2725);
DISPLAY 0.872340 (-2250 2725);
PAINT GREEN (-2250 2725);
DISPLAY INVISIBLE (-2250 2725);
FORCEPROP 1 LAST HDL_TAP TRUE
J 2
(-2575 2550);
DISPLAY 0.872340 (-2575 2550);
DISPLAY INVISIBLE (-2575 2550);
FORCEPROP 1 LAST PATH I39
J 2
(-2248 2675);
DISPLAY 0.872340 (-2248 2675);
PAINT GREEN (-2248 2675);
DISPLAY INVISIBLE (-2248 2675);
FORCEADD TAP..1
R 2
(-2100 -500);
FORCEPROP 3 LASTPIN (-2050 -500) SIG_NAME P3E_CPU0_P4_TX_DP<3>
J 0
(-2040 -490);
DISPLAY 0.659574 (-2040 -490);
PAINT MONO (-2040 -490);
DISPLAY INVISIBLE (-2040 -490);
FORCEPROP 1 LASTPIN (-2050 -500) BN 3
J 2
(-2038 -492);
DISPLAY 0.680851 (-2038 -492);
PAINT MONO (-2038 -492);
FORCEPROP 2 LAST CDS_LIB standard
J 0
(-2100 -500);
DISPLAY INVISIBLE (-2100 -500);
FORCEPROP 1 LAST BODY_TYPE PLUMBING
J 2
(-2100 -450);
DISPLAY 0.872340 (-2100 -450);
PAINT GREEN (-2100 -450);
DISPLAY INVISIBLE (-2100 -450);
FORCEPROP 1 LAST HDL_TAP TRUE
J 2
(-2425 -625);
DISPLAY 0.872340 (-2425 -625);
DISPLAY INVISIBLE (-2425 -625);
FORCEPROP 1 LAST PATH I4
J 2
(-2098 -500);
DISPLAY 0.872340 (-2098 -500);
PAINT GREEN (-2098 -500);
DISPLAY INVISIBLE (-2098 -500);
FORCEADD TAP..1
R 2
(-2250 2875);
FORCEPROP 3 LASTPIN (-2200 2875) SIG_NAME P5E_CPU1_P3_TX_DN<7>
J 0
(-2190 2885);
DISPLAY 0.659574 (-2190 2885);
PAINT MONO (-2190 2885);
DISPLAY INVISIBLE (-2190 2885);
FORCEPROP 1 LASTPIN (-2200 2875) BN 7
J 2
(-2188 2883);
DISPLAY 0.680851 (-2188 2883);
PAINT GREEN (-2188 2883);
FORCEPROP 2 LAST CDS_LIB standard
J 0
(-2250 2875);
DISPLAY INVISIBLE (-2250 2875);
FORCEPROP 1 LAST BODY_TYPE PLUMBING
J 2
(-2250 2925);
DISPLAY 0.872340 (-2250 2925);
PAINT GREEN (-2250 2925);
DISPLAY INVISIBLE (-2250 2925);
FORCEPROP 1 LAST HDL_TAP TRUE
J 2
(-2575 2750);
DISPLAY 0.872340 (-2575 2750);
DISPLAY INVISIBLE (-2575 2750);
FORCEPROP 1 LAST PATH I40
J 2
(-2248 2875);
DISPLAY 0.872340 (-2248 2875);
PAINT GREEN (-2248 2875);
DISPLAY INVISIBLE (-2248 2875);
FORCEADD TAP..1
R 2
(-2475 3050);
FORCEPROP 3 LASTPIN (-2425 3050) SIG_NAME P5E_CPU1_P3_TX_DP<8>
J 0
(-2415 3060);
DISPLAY 0.659574 (-2415 3060);
PAINT MONO (-2415 3060);
DISPLAY INVISIBLE (-2415 3060);
FORCEPROP 1 LASTPIN (-2425 3050) BN 8
J 2
(-2413 3058);
DISPLAY 0.680851 (-2413 3058);
PAINT GREEN (-2413 3058);
FORCEPROP 2 LAST CDS_LIB standard
J 0
(-2475 3050);
DISPLAY INVISIBLE (-2475 3050);
FORCEPROP 1 LAST BODY_TYPE PLUMBING
J 2
(-2475 3100);
DISPLAY 0.872340 (-2475 3100);
PAINT GREEN (-2475 3100);
DISPLAY INVISIBLE (-2475 3100);
FORCEPROP 1 LAST HDL_TAP TRUE
J 2
(-2800 2925);
DISPLAY 0.872340 (-2800 2925);
DISPLAY INVISIBLE (-2800 2925);
FORCEPROP 1 LAST PATH I41
J 2
(-2473 3050);
DISPLAY 0.872340 (-2473 3050);
PAINT GREEN (-2473 3050);
DISPLAY INVISIBLE (-2473 3050);
FORCEADD TAP..1
R 2
(-2475 3250);
FORCEPROP 3 LASTPIN (-2425 3250) SIG_NAME P5E_CPU1_P3_TX_DP<9>
J 0
(-2415 3260);
DISPLAY 0.659574 (-2415 3260);
PAINT MONO (-2415 3260);
DISPLAY INVISIBLE (-2415 3260);
FORCEPROP 1 LASTPIN (-2425 3250) BN 9
J 2
(-2413 3258);
DISPLAY 0.680851 (-2413 3258);
PAINT GREEN (-2413 3258);
FORCEPROP 2 LAST CDS_LIB standard
J 0
(-2475 3250);
DISPLAY INVISIBLE (-2475 3250);
FORCEPROP 1 LAST BODY_TYPE PLUMBING
J 2
(-2475 3300);
DISPLAY 0.872340 (-2475 3300);
PAINT GREEN (-2475 3300);
DISPLAY INVISIBLE (-2475 3300);
FORCEPROP 1 LAST HDL_TAP TRUE
J 2
(-2800 3125);
DISPLAY 0.872340 (-2800 3125);
DISPLAY INVISIBLE (-2800 3125);
FORCEPROP 1 LAST PATH I42
J 2
(-2473 3250);
DISPLAY 0.872340 (-2473 3250);
PAINT GREEN (-2473 3250);
DISPLAY INVISIBLE (-2473 3250);
FORCEADD TAP..1
R 2
(-2475 3450);
FORCEPROP 3 LASTPIN (-2425 3450) SIG_NAME P5E_CPU1_P3_TX_DP<10>
J 0
(-2415 3460);
DISPLAY 0.659574 (-2415 3460);
PAINT MONO (-2415 3460);
DISPLAY INVISIBLE (-2415 3460);
FORCEPROP 1 LASTPIN (-2425 3450) BN 10
J 2
(-2413 3458);
DISPLAY 0.680851 (-2413 3458);
PAINT GREEN (-2413 3458);
FORCEPROP 2 LAST CDS_LIB standard
J 0
(-2475 3450);
DISPLAY INVISIBLE (-2475 3450);
FORCEPROP 1 LAST BODY_TYPE PLUMBING
J 2
(-2475 3500);
DISPLAY 0.872340 (-2475 3500);
PAINT GREEN (-2475 3500);
DISPLAY INVISIBLE (-2475 3500);
FORCEPROP 1 LAST HDL_TAP TRUE
J 2
(-2800 3325);
DISPLAY 0.872340 (-2800 3325);
DISPLAY INVISIBLE (-2800 3325);
FORCEPROP 1 LAST PATH I43
J 2
(-2473 3450);
DISPLAY 0.872340 (-2473 3450);
PAINT GREEN (-2473 3450);
DISPLAY INVISIBLE (-2473 3450);
FORCEADD TAP..1
R 2
(-2225 3100);
FORCEPROP 3 LASTPIN (-2175 3100) SIG_NAME P5E_CPU1_P3_TX_DN<8>
J 0
(-2165 3110);
DISPLAY 0.659574 (-2165 3110);
PAINT MONO (-2165 3110);
DISPLAY INVISIBLE (-2165 3110);
FORCEPROP 1 LASTPIN (-2175 3100) BN 8
J 2
(-2163 3108);
DISPLAY 0.680851 (-2163 3108);
PAINT GREEN (-2163 3108);
FORCEPROP 2 LAST CDS_LIB standard
J 0
(-2225 3100);
DISPLAY INVISIBLE (-2225 3100);
FORCEPROP 1 LAST BODY_TYPE PLUMBING
J 2
(-2225 3150);
DISPLAY 0.872340 (-2225 3150);
PAINT GREEN (-2225 3150);
DISPLAY INVISIBLE (-2225 3150);
FORCEPROP 1 LAST HDL_TAP TRUE
J 2
(-2550 2975);
DISPLAY 0.872340 (-2550 2975);
DISPLAY INVISIBLE (-2550 2975);
FORCEPROP 1 LAST PATH I44
J 2
(-2223 3100);
DISPLAY 0.872340 (-2223 3100);
PAINT GREEN (-2223 3100);
DISPLAY INVISIBLE (-2223 3100);
FORCEADD TAP..1
R 2
(-2225 3300);
FORCEPROP 3 LASTPIN (-2175 3300) SIG_NAME P5E_CPU1_P3_TX_DN<9>
J 0
(-2165 3310);
DISPLAY 0.659574 (-2165 3310);
PAINT MONO (-2165 3310);
DISPLAY INVISIBLE (-2165 3310);
FORCEPROP 1 LASTPIN (-2175 3300) BN 9
J 2
(-2163 3308);
DISPLAY 0.680851 (-2163 3308);
PAINT GREEN (-2163 3308);
FORCEPROP 2 LAST CDS_LIB standard
J 0
(-2225 3300);
DISPLAY INVISIBLE (-2225 3300);
FORCEPROP 1 LAST BODY_TYPE PLUMBING
J 2
(-2225 3350);
DISPLAY 0.872340 (-2225 3350);
PAINT GREEN (-2225 3350);
DISPLAY INVISIBLE (-2225 3350);
FORCEPROP 1 LAST HDL_TAP TRUE
J 2
(-2550 3175);
DISPLAY 0.872340 (-2550 3175);
DISPLAY INVISIBLE (-2550 3175);
FORCEPROP 1 LAST PATH I45
J 2
(-2223 3300);
DISPLAY 0.872340 (-2223 3300);
PAINT GREEN (-2223 3300);
DISPLAY INVISIBLE (-2223 3300);
FORCEADD TAP..1
R 2
(-2225 3500);
FORCEPROP 3 LASTPIN (-2175 3500) SIG_NAME P5E_CPU1_P3_TX_DN<10>
J 0
(-2165 3510);
DISPLAY 0.659574 (-2165 3510);
PAINT MONO (-2165 3510);
DISPLAY INVISIBLE (-2165 3510);
FORCEPROP 1 LASTPIN (-2175 3500) BN 10
J 2
(-2163 3508);
DISPLAY 0.680851 (-2163 3508);
PAINT GREEN (-2163 3508);
FORCEPROP 2 LAST CDS_LIB standard
J 0
(-2225 3500);
DISPLAY INVISIBLE (-2225 3500);
FORCEPROP 1 LAST BODY_TYPE PLUMBING
J 2
(-2225 3550);
DISPLAY 0.872340 (-2225 3550);
PAINT GREEN (-2225 3550);
DISPLAY INVISIBLE (-2225 3550);
FORCEPROP 1 LAST HDL_TAP TRUE
J 2
(-2550 3375);
DISPLAY 0.872340 (-2550 3375);
DISPLAY INVISIBLE (-2550 3375);
FORCEPROP 1 LAST PATH I46
J 2
(-2223 3500);
DISPLAY 0.872340 (-2223 3500);
PAINT GREEN (-2223 3500);
DISPLAY INVISIBLE (-2223 3500);
FORCEADD TAP..1
R 2
(-2475 3650);
FORCEPROP 3 LASTPIN (-2425 3650) SIG_NAME P5E_CPU1_P3_TX_DP<11>
J 0
(-2415 3660);
DISPLAY 0.659574 (-2415 3660);
PAINT MONO (-2415 3660);
DISPLAY INVISIBLE (-2415 3660);
FORCEPROP 1 LASTPIN (-2425 3650) BN 11
J 2
(-2413 3658);
DISPLAY 0.680851 (-2413 3658);
PAINT GREEN (-2413 3658);
FORCEPROP 2 LAST CDS_LIB standard
J 0
(-2475 3650);
DISPLAY INVISIBLE (-2475 3650);
FORCEPROP 1 LAST BODY_TYPE PLUMBING
J 2
(-2475 3700);
DISPLAY 0.872340 (-2475 3700);
PAINT GREEN (-2475 3700);
DISPLAY INVISIBLE (-2475 3700);
FORCEPROP 1 LAST HDL_TAP TRUE
J 2
(-2800 3525);
DISPLAY 0.872340 (-2800 3525);
DISPLAY INVISIBLE (-2800 3525);
FORCEPROP 1 LAST PATH I47
J 2
(-2473 3650);
DISPLAY 0.872340 (-2473 3650);
PAINT GREEN (-2473 3650);
DISPLAY INVISIBLE (-2473 3650);
FORCEADD TAP..1
R 2
(-2475 3850);
FORCEPROP 3 LASTPIN (-2425 3850) SIG_NAME P5E_CPU1_P3_TX_DP<12>
J 0
(-2415 3860);
DISPLAY 0.659574 (-2415 3860);
PAINT MONO (-2415 3860);
DISPLAY INVISIBLE (-2415 3860);
FORCEPROP 1 LASTPIN (-2425 3850) BN 12
J 2
(-2413 3858);
DISPLAY 0.680851 (-2413 3858);
PAINT GREEN (-2413 3858);
FORCEPROP 2 LAST CDS_LIB standard
J 0
(-2475 3850);
DISPLAY INVISIBLE (-2475 3850);
FORCEPROP 1 LAST BODY_TYPE PLUMBING
J 2
(-2475 3900);
DISPLAY 0.872340 (-2475 3900);
PAINT GREEN (-2475 3900);
DISPLAY INVISIBLE (-2475 3900);
FORCEPROP 1 LAST HDL_TAP TRUE
J 2
(-2800 3725);
DISPLAY 0.872340 (-2800 3725);
DISPLAY INVISIBLE (-2800 3725);
FORCEPROP 1 LAST PATH I48
J 2
(-2473 3850);
DISPLAY 0.872340 (-2473 3850);
PAINT GREEN (-2473 3850);
DISPLAY INVISIBLE (-2473 3850);
FORCEADD TAP..1
R 2
(-2225 3700);
FORCEPROP 3 LASTPIN (-2175 3700) SIG_NAME P5E_CPU1_P3_TX_DN<11>
J 0
(-2165 3710);
DISPLAY 0.659574 (-2165 3710);
PAINT MONO (-2165 3710);
DISPLAY INVISIBLE (-2165 3710);
FORCEPROP 1 LASTPIN (-2175 3700) BN 11
J 2
(-2163 3708);
DISPLAY 0.680851 (-2163 3708);
PAINT GREEN (-2163 3708);
FORCEPROP 2 LAST CDS_LIB standard
J 0
(-2225 3700);
DISPLAY INVISIBLE (-2225 3700);
FORCEPROP 1 LAST BODY_TYPE PLUMBING
J 2
(-2225 3750);
DISPLAY 0.872340 (-2225 3750);
PAINT GREEN (-2225 3750);
DISPLAY INVISIBLE (-2225 3750);
FORCEPROP 1 LAST HDL_TAP TRUE
J 2
(-2550 3575);
DISPLAY 0.872340 (-2550 3575);
DISPLAY INVISIBLE (-2550 3575);
FORCEPROP 1 LAST PATH I49
J 2
(-2223 3700);
DISPLAY 0.872340 (-2223 3700);
PAINT GREEN (-2223 3700);
DISPLAY INVISIBLE (-2223 3700);
FORCEADD TAP..1
R 2
(-2100 -300);
FORCEPROP 3 LASTPIN (-2050 -300) SIG_NAME P3E_CPU0_P4_TX_DP<2>
J 0
(-2040 -290);
DISPLAY 0.659574 (-2040 -290);
PAINT MONO (-2040 -290);
DISPLAY INVISIBLE (-2040 -290);
FORCEPROP 1 LASTPIN (-2050 -300) BN 2
J 2
(-2038 -292);
DISPLAY 0.680851 (-2038 -292);
PAINT MONO (-2038 -292);
FORCEPROP 2 LAST CDS_LIB standard
J 0
(-2100 -300);
DISPLAY INVISIBLE (-2100 -300);
FORCEPROP 1 LAST BODY_TYPE PLUMBING
J 2
(-2100 -250);
DISPLAY 0.872340 (-2100 -250);
PAINT GREEN (-2100 -250);
DISPLAY INVISIBLE (-2100 -250);
FORCEPROP 1 LAST HDL_TAP TRUE
J 2
(-2425 -425);
DISPLAY 0.872340 (-2425 -425);
DISPLAY INVISIBLE (-2425 -425);
FORCEPROP 1 LAST PATH I5
J 2
(-2098 -300);
DISPLAY 0.872340 (-2098 -300);
PAINT GREEN (-2098 -300);
DISPLAY INVISIBLE (-2098 -300);
FORCEADD TAP..1
R 2
(-2225 3900);
FORCEPROP 3 LASTPIN (-2175 3900) SIG_NAME P5E_CPU1_P3_TX_DN<12>
J 0
(-2165 3910);
DISPLAY 0.659574 (-2165 3910);
PAINT MONO (-2165 3910);
DISPLAY INVISIBLE (-2165 3910);
FORCEPROP 1 LASTPIN (-2175 3900) BN 12
J 2
(-2163 3908);
DISPLAY 0.680851 (-2163 3908);
PAINT GREEN (-2163 3908);
FORCEPROP 2 LAST CDS_LIB standard
J 0
(-2225 3900);
DISPLAY INVISIBLE (-2225 3900);
FORCEPROP 1 LAST BODY_TYPE PLUMBING
J 2
(-2225 3950);
DISPLAY 0.872340 (-2225 3950);
PAINT GREEN (-2225 3950);
DISPLAY INVISIBLE (-2225 3950);
FORCEPROP 1 LAST HDL_TAP TRUE
J 2
(-2550 3775);
DISPLAY 0.872340 (-2550 3775);
DISPLAY INVISIBLE (-2550 3775);
FORCEPROP 1 LAST PATH I50
J 2
(-2223 3900);
DISPLAY 0.872340 (-2223 3900);
PAINT GREEN (-2223 3900);
DISPLAY INVISIBLE (-2223 3900);
FORCEADD Q_CAP_DIFFBUS..2
R 2
(-1375 50);
FORCEPROP 1 LAST LOCATION C1996
J 2
(-1150 50);
DISPLAY 0.723404 (-1150 50);
PAINT GREEN (-1150 50);
FORCEPROP 0 LAST $SEC 1
J 0
(-1150 100);
DISPLAY 0.680851 (-1150 100);
PAINT MONO (-1150 100);
DISPLAY INVISIBLE (-1150 100);
FORCEPROP 0 LAST CDS_SEC 1
J 0
(-1150 100);
DISPLAY 0.680851 (-1150 100);
DISPLAY INVISIBLE (-1150 100);
FORCEPROP 0 LASTPIN (-1300 50) $PN 1
J 0
(-1290 60);
DISPLAY 0.680851 (-1290 60);
PAINT MONO (-1290 60);
FORCEPROP 0 LASTPIN (-1450 50) $PN 2
J 2
(-1460 60);
DISPLAY 0.680851 (-1460 60);
PAINT MONO (-1460 60);
FORCEPROP 2 LAST VALUE DIFF BUS_0.22UF
J 2
(-1525 50);
DISPLAY 0.553191 (-1525 50);
FORCEPROP 2 LAST CDS_LIB pure_quanta
J 0
(-1375 50);
DISPLAY INVISIBLE (-1375 50);
FORCEPROP 1 LAST CDS_LMAN_SYM_OUTLINE -25,50,25,-50
J 2
(-1375 50);
DISPLAY 0.468085 (-1375 50);
PAINT GREEN (-1375 50);
DISPLAY INVISIBLE (-1375 50);
FORCEPROP 1 LAST PIN_NAMES_ROTATE TRUE
J 2
(-1375 50);
DISPLAY 0.489362 (-1375 50);
PAINT GREEN (-1375 50);
DISPLAY INVISIBLE (-1375 50);
FORCEPROP 2 LAST VOLTAGE 6.3V
J 2
(-1725 100);
DISPLAY 0.553191 (-1725 100);
DISPLAY INVISIBLE (-1725 100);
FORCEPROP 1 LAST MATERIAL X6S
J 2
(-1366 129);
DISPLAY 0.574468 (-1366 129);
PAINT GREEN (-1366 129);
DISPLAY INVISIBLE (-1366 129);
FORCEPROP 2 LAST PACK_TYPE C0201
J 2
(-1550 100);
DISPLAY 0.553191 (-1550 100);
DISPLAY INVISIBLE (-1550 100);
FORCEPROP 2 LAST TOLERANCE 20%
J 2
(-1450 100);
DISPLAY 0.553191 (-1450 100);
DISPLAY INVISIBLE (-1450 100);
FORCEPROP 1 LAST PART_NUMBER SP_CH4221MEE01
J 2
(-1491 138);
DISPLAY 0.574468 (-1491 138);
PAINT GREEN (-1491 138);
DISPLAY INVISIBLE (-1491 138);
FORCEPROP 1 LAST PATH I51
J 2
(-1375 50);
DISPLAY 0.723404 (-1375 50);
DISPLAY INVISIBLE (-1375 50);
FORCEADD Q_CAP_DIFFBUS..2
R 2
(-1375 100);
FORCEPROP 1 LAST LOCATION C1995
J 2
(-1150 100);
DISPLAY 0.723404 (-1150 100);
PAINT GREEN (-1150 100);
FORCEPROP 0 LAST $SEC 1
J 0
(-1400 350);
DISPLAY 0.680851 (-1400 350);
PAINT MONO (-1400 350);
DISPLAY INVISIBLE (-1400 350);
FORCEPROP 0 LAST CDS_SEC 1
J 0
(-1400 350);
DISPLAY 0.680851 (-1400 350);
DISPLAY INVISIBLE (-1400 350);
FORCEPROP 0 LASTPIN (-1300 100) $PN 1
J 0
(-1290 110);
DISPLAY 0.680851 (-1290 110);
PAINT MONO (-1290 110);
FORCEPROP 0 LASTPIN (-1450 100) $PN 2
J 2
(-1460 110);
DISPLAY 0.680851 (-1460 110);
PAINT MONO (-1460 110);
FORCEPROP 2 LAST VALUE DIFF BUS_0.22UF
J 2
(-1525 100);
DISPLAY 0.553191 (-1525 100);
FORCEPROP 2 LAST VOLTAGE 6.3V
J 2
(-1125 250);
DISPLAY 0.553191 (-1125 250);
PAINT GREEN (-1125 250);
FORCEPROP 2 LAST PACK_TYPE C0201
J 2
(-1375 250);
DISPLAY 0.553191 (-1375 250);
PAINT GREEN (-1375 250);
FORCEPROP 2 LAST TOLERANCE 20%
J 2
(-1275 250);
DISPLAY 0.553191 (-1275 250);
PAINT GREEN (-1275 250);
FORCEPROP 1 LAST MATERIAL X6S
J 2
(-1416 304);
DISPLAY 0.574468 (-1416 304);
PAINT GREEN (-1416 304);
FORCEPROP 2 LAST CDS_LIB pure_quanta
J 0
(-1375 100);
DISPLAY INVISIBLE (-1375 100);
FORCEPROP 1 LAST CDS_LMAN_SYM_OUTLINE -25,50,25,-50
J 2
(-1375 100);
DISPLAY 0.468085 (-1375 100);
PAINT GREEN (-1375 100);
DISPLAY INVISIBLE (-1375 100);
FORCEPROP 1 LAST PIN_NAMES_ROTATE TRUE
J 2
(-1375 100);
DISPLAY 0.489362 (-1375 100);
PAINT GREEN (-1375 100);
DISPLAY INVISIBLE (-1375 100);
FORCEPROP 1 LAST PART_NUMBER SP_CH4221MEE01
J 2
(-1116 188);
DISPLAY 0.574468 (-1116 188);
PAINT GREEN (-1116 188);
DISPLAY INVISIBLE (-1116 188);
FORCEPROP 1 LAST PATH I52
J 2
(-1375 100);
DISPLAY 0.723404 (-1375 100);
DISPLAY INVISIBLE (-1375 100);
FORCEADD Q_CAP_DIFFBUS..2
R 2
(-1525 1425);
FORCEPROP 1 LAST LOCATION C1547
J 2
(-1275 1450);
DISPLAY 0.723404 (-1275 1450);
PAINT GREEN (-1275 1450);
FORCEPROP 2 LAST $SEC 1
J 2
(-1350 1500);
DISPLAY 0.680851 (-1350 1500);
PAINT MONO (-1350 1500);
DISPLAY INVISIBLE (-1350 1500);
FORCEPROP 2 LAST CDS_SEC 1
J 2
(-1350 1500);
DISPLAY 0.680851 (-1350 1500);
DISPLAY INVISIBLE (-1350 1500);
FORCEPROP 2 LASTPIN (-1450 1425) $PN 1
J 0
(-1440 1435);
DISPLAY 0.808511 (-1440 1435);
FORCEPROP 2 LASTPIN (-1600 1425) $PN 2
J 2
(-1610 1435);
DISPLAY 0.808511 (-1610 1435);
FORCEPROP 2 LAST VALUE DIFF BUS_0.22UF
J 2
(-1675 1425);
DISPLAY 0.553191 (-1675 1425);
FORCEPROP 1 LAST PIN_NAMES_ROTATE TRUE
J 2
(-1525 1425);
DISPLAY 0.489362 (-1525 1425);
PAINT GREEN (-1525 1425);
DISPLAY INVISIBLE (-1525 1425);
FORCEPROP 2 LAST CDS_LIB pure_quanta
J 2
(-1525 1425);
DISPLAY INVISIBLE (-1525 1425);
FORCEPROP 1 LAST CDS_LMAN_SYM_OUTLINE -25,50,25,-50
J 2
(-1525 1425);
DISPLAY 0.468085 (-1525 1425);
PAINT GREEN (-1525 1425);
DISPLAY INVISIBLE (-1525 1425);
FORCEPROP 2 LAST VOLTAGE 6.3V
J 2
(-1875 1475);
DISPLAY 0.553191 (-1875 1475);
DISPLAY INVISIBLE (-1875 1475);
FORCEPROP 1 LAST MATERIAL X6S
J 2
(-1516 1504);
DISPLAY 0.574468 (-1516 1504);
PAINT GREEN (-1516 1504);
DISPLAY INVISIBLE (-1516 1504);
FORCEPROP 2 LAST PACK_TYPE C0201
J 2
(-1700 1475);
DISPLAY 0.553191 (-1700 1475);
DISPLAY INVISIBLE (-1700 1475);
FORCEPROP 2 LAST TOLERANCE 20%
J 2
(-1600 1475);
DISPLAY 0.553191 (-1600 1475);
DISPLAY INVISIBLE (-1600 1475);
FORCEPROP 1 LAST PART_NUMBER SP_CH4221MEE01
J 2
(-1641 1513);
DISPLAY 0.574468 (-1641 1513);
PAINT GREEN (-1641 1513);
DISPLAY INVISIBLE (-1641 1513);
FORCEPROP 1 LAST PATH I53
J 2
(-1525 1425);
DISPLAY 0.723404 (-1525 1425);
DISPLAY INVISIBLE (-1525 1425);
FORCEADD Q_CAP_DIFFBUS..2
R 2
(-1525 1475);
FORCEPROP 1 LAST LOCATION C1546
J 2
(-1275 1500);
DISPLAY 0.723404 (-1275 1500);
PAINT GREEN (-1275 1500);
FORCEPROP 2 LAST $SEC 1
J 2
(-1350 1550);
DISPLAY 0.680851 (-1350 1550);
PAINT MONO (-1350 1550);
DISPLAY INVISIBLE (-1350 1550);
FORCEPROP 2 LAST CDS_SEC 1
J 2
(-1350 1550);
DISPLAY 0.680851 (-1350 1550);
DISPLAY INVISIBLE (-1350 1550);
FORCEPROP 2 LASTPIN (-1450 1475) $PN 1
J 0
(-1440 1485);
DISPLAY 0.808511 (-1440 1485);
FORCEPROP 2 LASTPIN (-1600 1475) $PN 2
J 2
(-1610 1485);
DISPLAY 0.808511 (-1610 1485);
FORCEPROP 2 LAST VALUE DIFF BUS_0.22UF
J 2
(-1675 1475);
DISPLAY 0.553191 (-1675 1475);
FORCEPROP 1 LAST PIN_NAMES_ROTATE TRUE
J 2
(-1525 1475);
DISPLAY 0.489362 (-1525 1475);
PAINT GREEN (-1525 1475);
DISPLAY INVISIBLE (-1525 1475);
FORCEPROP 2 LAST CDS_LIB pure_quanta
J 2
(-1525 1475);
DISPLAY INVISIBLE (-1525 1475);
FORCEPROP 1 LAST CDS_LMAN_SYM_OUTLINE -25,50,25,-50
J 2
(-1525 1475);
DISPLAY 0.468085 (-1525 1475);
PAINT GREEN (-1525 1475);
DISPLAY INVISIBLE (-1525 1475);
FORCEPROP 2 LAST VOLTAGE 6.3V
J 2
(-1875 1525);
DISPLAY 0.553191 (-1875 1525);
DISPLAY INVISIBLE (-1875 1525);
FORCEPROP 1 LAST MATERIAL X6S
J 2
(-1516 1554);
DISPLAY 0.574468 (-1516 1554);
PAINT GREEN (-1516 1554);
DISPLAY INVISIBLE (-1516 1554);
FORCEPROP 2 LAST PACK_TYPE C0201
J 2
(-1700 1525);
DISPLAY 0.553191 (-1700 1525);
DISPLAY INVISIBLE (-1700 1525);
FORCEPROP 2 LAST TOLERANCE 20%
J 2
(-1600 1525);
DISPLAY 0.553191 (-1600 1525);
DISPLAY INVISIBLE (-1600 1525);
FORCEPROP 1 LAST PART_NUMBER SP_CH4221MEE01
J 2
(-1641 1563);
DISPLAY 0.574468 (-1641 1563);
PAINT GREEN (-1641 1563);
DISPLAY INVISIBLE (-1641 1563);
FORCEPROP 1 LAST PATH I54
J 2
(-1525 1475);
DISPLAY 0.723404 (-1525 1475);
DISPLAY INVISIBLE (-1525 1475);
FORCEADD Q_CAP_DIFFBUS..2
R 2
(-1525 1675);
FORCEPROP 1 LAST LOCATION C1544
J 2
(-1275 1700);
DISPLAY 0.723404 (-1275 1700);
PAINT GREEN (-1275 1700);
FORCEPROP 2 LAST $SEC 1
J 2
(-1350 1750);
DISPLAY 0.680851 (-1350 1750);
PAINT MONO (-1350 1750);
DISPLAY INVISIBLE (-1350 1750);
FORCEPROP 2 LAST CDS_SEC 1
J 2
(-1350 1750);
DISPLAY 0.680851 (-1350 1750);
DISPLAY INVISIBLE (-1350 1750);
FORCEPROP 2 LASTPIN (-1450 1675) $PN 1
J 0
(-1440 1685);
DISPLAY 0.808511 (-1440 1685);
FORCEPROP 2 LASTPIN (-1600 1675) $PN 2
J 2
(-1610 1685);
DISPLAY 0.808511 (-1610 1685);
FORCEPROP 2 LAST VALUE DIFF BUS_0.22UF
J 2
(-1675 1675);
DISPLAY 0.553191 (-1675 1675);
FORCEPROP 1 LAST PIN_NAMES_ROTATE TRUE
J 2
(-1525 1675);
DISPLAY 0.489362 (-1525 1675);
PAINT GREEN (-1525 1675);
DISPLAY INVISIBLE (-1525 1675);
FORCEPROP 1 LAST CDS_LMAN_SYM_OUTLINE -25,50,25,-50
J 2
(-1525 1675);
DISPLAY 0.468085 (-1525 1675);
PAINT GREEN (-1525 1675);
DISPLAY INVISIBLE (-1525 1675);
FORCEPROP 2 LAST CDS_LIB pure_quanta
J 2
(-1525 1675);
DISPLAY INVISIBLE (-1525 1675);
FORCEPROP 2 LAST VOLTAGE 6.3V
J 2
(-1875 1725);
DISPLAY 0.553191 (-1875 1725);
DISPLAY INVISIBLE (-1875 1725);
FORCEPROP 1 LAST MATERIAL X6S
J 2
(-1516 1754);
DISPLAY 0.574468 (-1516 1754);
PAINT GREEN (-1516 1754);
DISPLAY INVISIBLE (-1516 1754);
FORCEPROP 2 LAST PACK_TYPE C0201
J 2
(-1700 1725);
DISPLAY 0.553191 (-1700 1725);
DISPLAY INVISIBLE (-1700 1725);
FORCEPROP 2 LAST TOLERANCE 20%
J 2
(-1600 1725);
DISPLAY 0.553191 (-1600 1725);
DISPLAY INVISIBLE (-1600 1725);
FORCEPROP 1 LAST PART_NUMBER SP_CH4221MEE01
J 2
(-1641 1763);
DISPLAY 0.574468 (-1641 1763);
PAINT GREEN (-1641 1763);
DISPLAY INVISIBLE (-1641 1763);
FORCEPROP 1 LAST PATH I55
J 2
(-1525 1675);
DISPLAY 0.723404 (-1525 1675);
DISPLAY INVISIBLE (-1525 1675);
FORCEADD Q_CAP_DIFFBUS..2
R 2
(-1525 1625);
FORCEPROP 1 LAST LOCATION C1545
J 2
(-1275 1650);
DISPLAY 0.723404 (-1275 1650);
PAINT GREEN (-1275 1650);
FORCEPROP 2 LAST $SEC 1
J 2
(-1350 1700);
DISPLAY 0.680851 (-1350 1700);
PAINT MONO (-1350 1700);
DISPLAY INVISIBLE (-1350 1700);
FORCEPROP 2 LAST CDS_SEC 1
J 2
(-1350 1700);
DISPLAY 0.680851 (-1350 1700);
DISPLAY INVISIBLE (-1350 1700);
FORCEPROP 2 LASTPIN (-1450 1625) $PN 1
J 0
(-1440 1635);
DISPLAY 0.808511 (-1440 1635);
FORCEPROP 2 LASTPIN (-1600 1625) $PN 2
J 2
(-1610 1635);
DISPLAY 0.808511 (-1610 1635);
FORCEPROP 2 LAST VALUE DIFF BUS_0.22UF
J 2
(-1675 1625);
DISPLAY 0.553191 (-1675 1625);
FORCEPROP 1 LAST PIN_NAMES_ROTATE TRUE
J 2
(-1525 1625);
DISPLAY 0.489362 (-1525 1625);
PAINT GREEN (-1525 1625);
DISPLAY INVISIBLE (-1525 1625);
FORCEPROP 2 LAST CDS_LIB pure_quanta
J 2
(-1525 1625);
DISPLAY INVISIBLE (-1525 1625);
FORCEPROP 1 LAST CDS_LMAN_SYM_OUTLINE -25,50,25,-50
J 2
(-1525 1625);
DISPLAY 0.468085 (-1525 1625);
PAINT GREEN (-1525 1625);
DISPLAY INVISIBLE (-1525 1625);
FORCEPROP 2 LAST VOLTAGE 6.3V
J 2
(-1875 1675);
DISPLAY 0.553191 (-1875 1675);
DISPLAY INVISIBLE (-1875 1675);
FORCEPROP 1 LAST MATERIAL X6S
J 2
(-1516 1704);
DISPLAY 0.574468 (-1516 1704);
PAINT GREEN (-1516 1704);
DISPLAY INVISIBLE (-1516 1704);
FORCEPROP 2 LAST PACK_TYPE C0201
J 2
(-1700 1675);
DISPLAY 0.553191 (-1700 1675);
DISPLAY INVISIBLE (-1700 1675);
FORCEPROP 2 LAST TOLERANCE 20%
J 2
(-1600 1675);
DISPLAY 0.553191 (-1600 1675);
DISPLAY INVISIBLE (-1600 1675);
FORCEPROP 1 LAST PART_NUMBER SP_CH4221MEE01
J 2
(-1641 1713);
DISPLAY 0.574468 (-1641 1713);
PAINT GREEN (-1641 1713);
DISPLAY INVISIBLE (-1641 1713);
FORCEPROP 1 LAST PATH I56
J 2
(-1525 1625);
DISPLAY 0.723404 (-1525 1625);
DISPLAY INVISIBLE (-1525 1625);
FORCEADD Q_CAP_DIFFBUS..2
R 2
(-1525 1825);
FORCEPROP 1 LAST LOCATION C1543
J 2
(-1275 1850);
DISPLAY 0.723404 (-1275 1850);
PAINT GREEN (-1275 1850);
FORCEPROP 2 LAST $SEC 1
J 2
(-1350 1900);
DISPLAY 0.680851 (-1350 1900);
PAINT MONO (-1350 1900);
DISPLAY INVISIBLE (-1350 1900);
FORCEPROP 2 LAST CDS_SEC 1
J 2
(-1350 1900);
DISPLAY 0.680851 (-1350 1900);
DISPLAY INVISIBLE (-1350 1900);
FORCEPROP 2 LASTPIN (-1450 1825) $PN 1
J 0
(-1440 1835);
DISPLAY 0.808511 (-1440 1835);
FORCEPROP 2 LASTPIN (-1600 1825) $PN 2
J 2
(-1610 1835);
DISPLAY 0.808511 (-1610 1835);
FORCEPROP 2 LAST VALUE DIFF BUS_0.22UF
J 2
(-1675 1825);
DISPLAY 0.553191 (-1675 1825);
FORCEPROP 1 LAST PIN_NAMES_ROTATE TRUE
J 2
(-1525 1825);
DISPLAY 0.489362 (-1525 1825);
PAINT GREEN (-1525 1825);
DISPLAY INVISIBLE (-1525 1825);
FORCEPROP 2 LAST CDS_LIB pure_quanta
J 2
(-1525 1825);
DISPLAY INVISIBLE (-1525 1825);
FORCEPROP 1 LAST CDS_LMAN_SYM_OUTLINE -25,50,25,-50
J 2
(-1525 1825);
DISPLAY 0.468085 (-1525 1825);
PAINT GREEN (-1525 1825);
DISPLAY INVISIBLE (-1525 1825);
FORCEPROP 2 LAST VOLTAGE 6.3V
J 2
(-1875 1875);
DISPLAY 0.553191 (-1875 1875);
DISPLAY INVISIBLE (-1875 1875);
FORCEPROP 1 LAST MATERIAL X6S
J 2
(-1516 1904);
DISPLAY 0.574468 (-1516 1904);
PAINT GREEN (-1516 1904);
DISPLAY INVISIBLE (-1516 1904);
FORCEPROP 2 LAST PACK_TYPE C0201
J 2
(-1700 1875);
DISPLAY 0.553191 (-1700 1875);
DISPLAY INVISIBLE (-1700 1875);
FORCEPROP 2 LAST TOLERANCE 20%
J 2
(-1600 1875);
DISPLAY 0.553191 (-1600 1875);
DISPLAY INVISIBLE (-1600 1875);
FORCEPROP 1 LAST PART_NUMBER SP_CH4221MEE01
J 2
(-1641 1913);
DISPLAY 0.574468 (-1641 1913);
PAINT GREEN (-1641 1913);
DISPLAY INVISIBLE (-1641 1913);
FORCEPROP 1 LAST PATH I57
J 2
(-1525 1825);
DISPLAY 0.723404 (-1525 1825);
DISPLAY INVISIBLE (-1525 1825);
FORCEADD Q_CAP_DIFFBUS..2
R 2
(-1525 1875);
FORCEPROP 1 LAST LOCATION C1542
J 2
(-1275 1900);
DISPLAY 0.723404 (-1275 1900);
PAINT GREEN (-1275 1900);
FORCEPROP 2 LAST $SEC 1
J 2
(-1350 1950);
DISPLAY 0.680851 (-1350 1950);
PAINT MONO (-1350 1950);
DISPLAY INVISIBLE (-1350 1950);
FORCEPROP 2 LAST CDS_SEC 1
J 2
(-1350 1950);
DISPLAY 0.680851 (-1350 1950);
DISPLAY INVISIBLE (-1350 1950);
FORCEPROP 2 LASTPIN (-1450 1875) $PN 1
J 0
(-1440 1885);
DISPLAY 0.808511 (-1440 1885);
FORCEPROP 2 LASTPIN (-1600 1875) $PN 2
J 2
(-1610 1885);
DISPLAY 0.808511 (-1610 1885);
FORCEPROP 2 LAST VALUE DIFF BUS_0.22UF
J 2
(-1675 1875);
DISPLAY 0.553191 (-1675 1875);
FORCEPROP 1 LAST PIN_NAMES_ROTATE TRUE
J 2
(-1525 1875);
DISPLAY 0.489362 (-1525 1875);
PAINT GREEN (-1525 1875);
DISPLAY INVISIBLE (-1525 1875);
FORCEPROP 2 LAST CDS_LIB pure_quanta
J 2
(-1525 1875);
DISPLAY INVISIBLE (-1525 1875);
FORCEPROP 1 LAST CDS_LMAN_SYM_OUTLINE -25,50,25,-50
J 2
(-1525 1875);
DISPLAY 0.468085 (-1525 1875);
PAINT GREEN (-1525 1875);
DISPLAY INVISIBLE (-1525 1875);
FORCEPROP 2 LAST VOLTAGE 6.3V
J 2
(-1875 1925);
DISPLAY 0.553191 (-1875 1925);
DISPLAY INVISIBLE (-1875 1925);
FORCEPROP 1 LAST MATERIAL X6S
J 2
(-1516 1954);
DISPLAY 0.574468 (-1516 1954);
PAINT GREEN (-1516 1954);
DISPLAY INVISIBLE (-1516 1954);
FORCEPROP 2 LAST PACK_TYPE C0201
J 2
(-1700 1925);
DISPLAY 0.553191 (-1700 1925);
DISPLAY INVISIBLE (-1700 1925);
FORCEPROP 2 LAST TOLERANCE 20%
J 2
(-1600 1925);
DISPLAY 0.553191 (-1600 1925);
DISPLAY INVISIBLE (-1600 1925);
FORCEPROP 1 LAST PART_NUMBER SP_CH4221MEE01
J 2
(-1641 1963);
DISPLAY 0.574468 (-1641 1963);
PAINT GREEN (-1641 1963);
DISPLAY INVISIBLE (-1641 1963);
FORCEPROP 1 LAST PATH I58
J 2
(-1525 1875);
DISPLAY 0.723404 (-1525 1875);
DISPLAY INVISIBLE (-1525 1875);
FORCEADD TAP..1
(-825 100);
FORCEPROP 3 LASTPIN (-875 100) SIG_NAME P3E_CPU0_P4_TX_C_DP<0>
J 0
(-865 110);
DISPLAY 0.659574 (-865 110);
PAINT MONO (-865 110);
DISPLAY INVISIBLE (-865 110);
FORCEPROP 1 LASTPIN (-875 100) BN 0
J 0
(-887 108);
DISPLAY 0.680851 (-887 108);
PAINT MONO (-887 108);
FORCEPROP 2 LAST CDS_LIB standard
J 0
(-825 100);
DISPLAY INVISIBLE (-825 100);
FORCEPROP 1 LAST BODY_TYPE PLUMBING
J 0
(-825 150);
DISPLAY 0.872340 (-825 150);
PAINT GREEN (-825 150);
DISPLAY INVISIBLE (-825 150);
FORCEPROP 1 LAST HDL_TAP TRUE
J 0
(-500 -25);
DISPLAY 0.872340 (-500 -25);
DISPLAY INVISIBLE (-500 -25);
FORCEPROP 1 LAST PATH I59
J 0
(-827 100);
DISPLAY 0.872340 (-827 100);
PAINT GREEN (-827 100);
DISPLAY INVISIBLE (-827 100);
FORCEADD TAP..1
R 2
(-2100 -100);
FORCEPROP 3 LASTPIN (-2050 -100) SIG_NAME P3E_CPU0_P4_TX_DP<1>
J 0
(-2040 -90);
DISPLAY 0.659574 (-2040 -90);
PAINT MONO (-2040 -90);
DISPLAY INVISIBLE (-2040 -90);
FORCEPROP 1 LASTPIN (-2050 -100) BN 1
J 2
(-2038 -92);
DISPLAY 0.680851 (-2038 -92);
PAINT MONO (-2038 -92);
FORCEPROP 2 LAST CDS_LIB standard
J 0
(-2100 -100);
DISPLAY INVISIBLE (-2100 -100);
FORCEPROP 1 LAST BODY_TYPE PLUMBING
J 2
(-2100 -50);
DISPLAY 0.872340 (-2100 -50);
PAINT GREEN (-2100 -50);
DISPLAY INVISIBLE (-2100 -50);
FORCEPROP 1 LAST HDL_TAP TRUE
J 2
(-2425 -225);
DISPLAY 0.872340 (-2425 -225);
DISPLAY INVISIBLE (-2425 -225);
FORCEPROP 1 LAST PATH I6
J 2
(-2098 -100);
DISPLAY 0.872340 (-2098 -100);
PAINT GREEN (-2098 -100);
DISPLAY INVISIBLE (-2098 -100);
FORCEADD TAP..1
(-625 50);
FORCEPROP 3 LASTPIN (-675 50) SIG_NAME P3E_CPU0_P4_TX_C_DN<0>
J 0
(-665 60);
DISPLAY 0.659574 (-665 60);
PAINT MONO (-665 60);
DISPLAY INVISIBLE (-665 60);
FORCEPROP 1 LASTPIN (-675 50) BN 0
J 0
(-687 58);
DISPLAY 0.680851 (-687 58);
PAINT MONO (-687 58);
FORCEPROP 2 LAST CDS_LIB standard
J 0
(-625 50);
DISPLAY INVISIBLE (-625 50);
FORCEPROP 1 LAST BODY_TYPE PLUMBING
J 0
(-625 100);
DISPLAY 0.872340 (-625 100);
PAINT GREEN (-625 100);
DISPLAY INVISIBLE (-625 100);
FORCEPROP 1 LAST HDL_TAP TRUE
J 0
(-300 -75);
DISPLAY 0.872340 (-300 -75);
DISPLAY INVISIBLE (-300 -75);
FORCEPROP 1 LAST PATH I60
J 0
(-627 50);
DISPLAY 0.872340 (-627 50);
PAINT GREEN (-627 50);
DISPLAY INVISIBLE (-627 50);
FORCEADD TAP..1
(-775 1425);
FORCEPROP 3 LASTPIN (-825 1425) SIG_NAME P5E_CPU1_P3_TX_C_DP<0>
J 0
(-815 1435);
DISPLAY 0.659574 (-815 1435);
PAINT MONO (-815 1435);
DISPLAY INVISIBLE (-815 1435);
FORCEPROP 1 LASTPIN (-825 1425) BN 0
J 0
(-837 1433);
DISPLAY 0.680851 (-837 1433);
PAINT GREEN (-837 1433);
FORCEPROP 2 LAST CDS_LIB standard
J 0
(-775 1425);
DISPLAY INVISIBLE (-775 1425);
FORCEPROP 1 LAST BODY_TYPE PLUMBING
J 0
(-775 1475);
DISPLAY 0.872340 (-775 1475);
PAINT GREEN (-775 1475);
DISPLAY INVISIBLE (-775 1475);
FORCEPROP 1 LAST HDL_TAP TRUE
J 0
(-450 1300);
DISPLAY 0.872340 (-450 1300);
DISPLAY INVISIBLE (-450 1300);
FORCEPROP 1 LAST PATH I61
J 0
(-777 1425);
DISPLAY 0.872340 (-777 1425);
PAINT GREEN (-777 1425);
DISPLAY INVISIBLE (-777 1425);
FORCEADD TAP..1
(-975 1475);
FORCEPROP 3 LASTPIN (-1025 1475) SIG_NAME P5E_CPU1_P3_TX_C_DN<0>
J 0
(-1015 1485);
DISPLAY 0.659574 (-1015 1485);
PAINT MONO (-1015 1485);
DISPLAY INVISIBLE (-1015 1485);
FORCEPROP 1 LASTPIN (-1025 1475) BN 0
J 0
(-1037 1483);
DISPLAY 0.680851 (-1037 1483);
PAINT GREEN (-1037 1483);
FORCEPROP 2 LAST CDS_LIB standard
J 0
(-975 1475);
DISPLAY INVISIBLE (-975 1475);
FORCEPROP 1 LAST BODY_TYPE PLUMBING
J 0
(-975 1525);
DISPLAY 0.872340 (-975 1525);
PAINT GREEN (-975 1525);
DISPLAY INVISIBLE (-975 1525);
FORCEPROP 1 LAST HDL_TAP TRUE
J 0
(-650 1350);
DISPLAY 0.872340 (-650 1350);
DISPLAY INVISIBLE (-650 1350);
FORCEPROP 1 LAST PATH I62
J 0
(-977 1475);
DISPLAY 0.872340 (-977 1475);
PAINT GREEN (-977 1475);
DISPLAY INVISIBLE (-977 1475);
FORCEADD TAP..1
(-975 1675);
FORCEPROP 3 LASTPIN (-1025 1675) SIG_NAME P5E_CPU1_P3_TX_C_DN<1>
J 0
(-1015 1685);
DISPLAY 0.659574 (-1015 1685);
PAINT MONO (-1015 1685);
DISPLAY INVISIBLE (-1015 1685);
FORCEPROP 1 LASTPIN (-1025 1675) BN 1
J 0
(-1037 1683);
DISPLAY 0.680851 (-1037 1683);
PAINT GREEN (-1037 1683);
FORCEPROP 2 LAST CDS_LIB standard
J 0
(-975 1675);
DISPLAY INVISIBLE (-975 1675);
FORCEPROP 1 LAST BODY_TYPE PLUMBING
J 0
(-975 1725);
DISPLAY 0.872340 (-975 1725);
PAINT GREEN (-975 1725);
DISPLAY INVISIBLE (-975 1725);
FORCEPROP 1 LAST HDL_TAP TRUE
J 0
(-650 1550);
DISPLAY 0.872340 (-650 1550);
DISPLAY INVISIBLE (-650 1550);
FORCEPROP 1 LAST PATH I63
J 0
(-977 1675);
DISPLAY 0.872340 (-977 1675);
PAINT GREEN (-977 1675);
DISPLAY INVISIBLE (-977 1675);
FORCEADD TAP..1
(-975 1875);
FORCEPROP 3 LASTPIN (-1025 1875) SIG_NAME P5E_CPU1_P3_TX_C_DN<2>
J 0
(-1015 1885);
DISPLAY 0.659574 (-1015 1885);
PAINT MONO (-1015 1885);
DISPLAY INVISIBLE (-1015 1885);
FORCEPROP 1 LASTPIN (-1025 1875) BN 2
J 0
(-1037 1883);
DISPLAY 0.680851 (-1037 1883);
PAINT GREEN (-1037 1883);
FORCEPROP 2 LAST CDS_LIB standard
J 0
(-975 1875);
DISPLAY INVISIBLE (-975 1875);
FORCEPROP 1 LAST BODY_TYPE PLUMBING
J 0
(-975 1925);
DISPLAY 0.872340 (-975 1925);
PAINT GREEN (-975 1925);
DISPLAY INVISIBLE (-975 1925);
FORCEPROP 1 LAST HDL_TAP TRUE
J 0
(-650 1750);
DISPLAY 0.872340 (-650 1750);
DISPLAY INVISIBLE (-650 1750);
FORCEPROP 1 LAST PATH I64
J 0
(-977 1875);
DISPLAY 0.872340 (-977 1875);
PAINT GREEN (-977 1875);
DISPLAY INVISIBLE (-977 1875);
FORCEADD TAP..1
(-775 1625);
FORCEPROP 3 LASTPIN (-825 1625) SIG_NAME P5E_CPU1_P3_TX_C_DP<1>
J 0
(-815 1635);
DISPLAY 0.659574 (-815 1635);
PAINT MONO (-815 1635);
DISPLAY INVISIBLE (-815 1635);
FORCEPROP 1 LASTPIN (-825 1625) BN 1
J 0
(-837 1633);
DISPLAY 0.680851 (-837 1633);
PAINT GREEN (-837 1633);
FORCEPROP 2 LAST CDS_LIB standard
J 0
(-775 1625);
DISPLAY INVISIBLE (-775 1625);
FORCEPROP 1 LAST BODY_TYPE PLUMBING
J 0
(-775 1675);
DISPLAY 0.872340 (-775 1675);
PAINT GREEN (-775 1675);
DISPLAY INVISIBLE (-775 1675);
FORCEPROP 1 LAST HDL_TAP TRUE
J 0
(-450 1500);
DISPLAY 0.872340 (-450 1500);
DISPLAY INVISIBLE (-450 1500);
FORCEPROP 1 LAST PATH I65
J 0
(-777 1625);
DISPLAY 0.872340 (-777 1625);
PAINT GREEN (-777 1625);
DISPLAY INVISIBLE (-777 1625);
FORCEADD TAP..1
(-775 1825);
FORCEPROP 3 LASTPIN (-825 1825) SIG_NAME P5E_CPU1_P3_TX_C_DP<2>
J 0
(-815 1835);
DISPLAY 0.659574 (-815 1835);
PAINT MONO (-815 1835);
DISPLAY INVISIBLE (-815 1835);
FORCEPROP 1 LASTPIN (-825 1825) BN 2
J 0
(-837 1833);
DISPLAY 0.680851 (-837 1833);
PAINT GREEN (-837 1833);
FORCEPROP 2 LAST CDS_LIB standard
J 0
(-775 1825);
DISPLAY INVISIBLE (-775 1825);
FORCEPROP 1 LAST BODY_TYPE PLUMBING
J 0
(-775 1875);
DISPLAY 0.872340 (-775 1875);
PAINT GREEN (-775 1875);
DISPLAY INVISIBLE (-775 1875);
FORCEPROP 1 LAST HDL_TAP TRUE
J 0
(-450 1700);
DISPLAY 0.872340 (-450 1700);
DISPLAY INVISIBLE (-450 1700);
FORCEPROP 1 LAST PATH I66
J 0
(-777 1825);
DISPLAY 0.872340 (-777 1825);
PAINT GREEN (-777 1825);
DISPLAY INVISIBLE (-777 1825);
FORCEADD Q_CAP_DIFFBUS..2
R 2
(-1525 2025);
FORCEPROP 1 LAST LOCATION C1541
J 2
(-1275 2050);
DISPLAY 0.723404 (-1275 2050);
PAINT GREEN (-1275 2050);
FORCEPROP 2 LAST $SEC 1
J 2
(-1350 2100);
DISPLAY 0.680851 (-1350 2100);
PAINT MONO (-1350 2100);
DISPLAY INVISIBLE (-1350 2100);
FORCEPROP 2 LAST CDS_SEC 1
J 2
(-1350 2100);
DISPLAY 0.680851 (-1350 2100);
DISPLAY INVISIBLE (-1350 2100);
FORCEPROP 2 LASTPIN (-1450 2025) $PN 1
J 0
(-1440 2035);
DISPLAY 0.808511 (-1440 2035);
FORCEPROP 2 LASTPIN (-1600 2025) $PN 2
J 2
(-1610 2035);
DISPLAY 0.808511 (-1610 2035);
FORCEPROP 2 LAST VALUE DIFF BUS_0.22UF
J 2
(-1675 2025);
DISPLAY 0.553191 (-1675 2025);
FORCEPROP 1 LAST PIN_NAMES_ROTATE TRUE
J 2
(-1525 2025);
DISPLAY 0.489362 (-1525 2025);
PAINT GREEN (-1525 2025);
DISPLAY INVISIBLE (-1525 2025);
FORCEPROP 1 LAST CDS_LMAN_SYM_OUTLINE -25,50,25,-50
J 2
(-1525 2025);
DISPLAY 0.468085 (-1525 2025);
PAINT GREEN (-1525 2025);
DISPLAY INVISIBLE (-1525 2025);
FORCEPROP 2 LAST CDS_LIB pure_quanta
J 2
(-1525 2025);
DISPLAY INVISIBLE (-1525 2025);
FORCEPROP 2 LAST VOLTAGE 6.3V
J 2
(-1875 2075);
DISPLAY 0.553191 (-1875 2075);
DISPLAY INVISIBLE (-1875 2075);
FORCEPROP 1 LAST MATERIAL X6S
J 2
(-1516 2104);
DISPLAY 0.574468 (-1516 2104);
PAINT GREEN (-1516 2104);
DISPLAY INVISIBLE (-1516 2104);
FORCEPROP 2 LAST PACK_TYPE C0201
J 2
(-1700 2075);
DISPLAY 0.553191 (-1700 2075);
DISPLAY INVISIBLE (-1700 2075);
FORCEPROP 2 LAST TOLERANCE 20%
J 2
(-1600 2075);
DISPLAY 0.553191 (-1600 2075);
DISPLAY INVISIBLE (-1600 2075);
FORCEPROP 1 LAST PART_NUMBER SP_CH4221MEE01
J 2
(-1641 2113);
DISPLAY 0.574468 (-1641 2113);
PAINT GREEN (-1641 2113);
DISPLAY INVISIBLE (-1641 2113);
FORCEPROP 1 LAST PATH I67
J 2
(-1525 2025);
DISPLAY 0.723404 (-1525 2025);
DISPLAY INVISIBLE (-1525 2025);
FORCEADD Q_CAP_DIFFBUS..2
R 2
(-1525 2075);
FORCEPROP 1 LAST LOCATION C1540
J 2
(-1275 2100);
DISPLAY 0.723404 (-1275 2100);
PAINT GREEN (-1275 2100);
FORCEPROP 2 LAST $SEC 1
J 2
(-1350 2150);
DISPLAY 0.680851 (-1350 2150);
PAINT MONO (-1350 2150);
DISPLAY INVISIBLE (-1350 2150);
FORCEPROP 2 LAST CDS_SEC 1
J 2
(-1350 2150);
DISPLAY 0.680851 (-1350 2150);
DISPLAY INVISIBLE (-1350 2150);
FORCEPROP 2 LASTPIN (-1450 2075) $PN 1
J 0
(-1440 2085);
DISPLAY 0.808511 (-1440 2085);
FORCEPROP 2 LASTPIN (-1600 2075) $PN 2
J 2
(-1610 2085);
DISPLAY 0.808511 (-1610 2085);
FORCEPROP 2 LAST VALUE DIFF BUS_0.22UF
J 2
(-1675 2075);
DISPLAY 0.553191 (-1675 2075);
FORCEPROP 1 LAST PIN_NAMES_ROTATE TRUE
J 2
(-1525 2075);
DISPLAY 0.489362 (-1525 2075);
PAINT GREEN (-1525 2075);
DISPLAY INVISIBLE (-1525 2075);
FORCEPROP 1 LAST CDS_LMAN_SYM_OUTLINE -25,50,25,-50
J 2
(-1525 2075);
DISPLAY 0.468085 (-1525 2075);
PAINT GREEN (-1525 2075);
DISPLAY INVISIBLE (-1525 2075);
FORCEPROP 2 LAST CDS_LIB pure_quanta
J 2
(-1525 2075);
DISPLAY INVISIBLE (-1525 2075);
FORCEPROP 2 LAST VOLTAGE 6.3V
J 2
(-1875 2125);
DISPLAY 0.553191 (-1875 2125);
DISPLAY INVISIBLE (-1875 2125);
FORCEPROP 1 LAST MATERIAL X6S
J 2
(-1516 2154);
DISPLAY 0.574468 (-1516 2154);
PAINT GREEN (-1516 2154);
DISPLAY INVISIBLE (-1516 2154);
FORCEPROP 2 LAST PACK_TYPE C0201
J 2
(-1700 2125);
DISPLAY 0.553191 (-1700 2125);
DISPLAY INVISIBLE (-1700 2125);
FORCEPROP 2 LAST TOLERANCE 20%
J 2
(-1600 2125);
DISPLAY 0.553191 (-1600 2125);
DISPLAY INVISIBLE (-1600 2125);
FORCEPROP 1 LAST PART_NUMBER SP_CH4221MEE01
J 2
(-1641 2163);
DISPLAY 0.574468 (-1641 2163);
PAINT GREEN (-1641 2163);
DISPLAY INVISIBLE (-1641 2163);
FORCEPROP 1 LAST PATH I68
J 2
(-1525 2075);
DISPLAY 0.723404 (-1525 2075);
DISPLAY INVISIBLE (-1525 2075);
FORCEADD Q_CAP_DIFFBUS..2
R 2
(-1525 2225);
FORCEPROP 1 LAST LOCATION C1539
J 2
(-1275 2250);
DISPLAY 0.723404 (-1275 2250);
PAINT GREEN (-1275 2250);
FORCEPROP 2 LAST $SEC 1
J 2
(-1350 2300);
DISPLAY 0.680851 (-1350 2300);
PAINT MONO (-1350 2300);
DISPLAY INVISIBLE (-1350 2300);
FORCEPROP 2 LAST CDS_SEC 1
J 2
(-1350 2300);
DISPLAY 0.680851 (-1350 2300);
DISPLAY INVISIBLE (-1350 2300);
FORCEPROP 2 LASTPIN (-1450 2225) $PN 1
J 0
(-1440 2235);
DISPLAY 0.808511 (-1440 2235);
FORCEPROP 2 LASTPIN (-1600 2225) $PN 2
J 2
(-1610 2235);
DISPLAY 0.808511 (-1610 2235);
FORCEPROP 2 LAST VALUE DIFF BUS_0.22UF
J 2
(-1675 2225);
DISPLAY 0.553191 (-1675 2225);
FORCEPROP 1 LAST PIN_NAMES_ROTATE TRUE
J 2
(-1525 2225);
DISPLAY 0.489362 (-1525 2225);
PAINT GREEN (-1525 2225);
DISPLAY INVISIBLE (-1525 2225);
FORCEPROP 2 LAST CDS_LIB pure_quanta
J 2
(-1525 2225);
DISPLAY INVISIBLE (-1525 2225);
FORCEPROP 1 LAST CDS_LMAN_SYM_OUTLINE -25,50,25,-50
J 2
(-1525 2225);
DISPLAY 0.468085 (-1525 2225);
PAINT GREEN (-1525 2225);
DISPLAY INVISIBLE (-1525 2225);
FORCEPROP 2 LAST VOLTAGE 6.3V
J 2
(-1875 2275);
DISPLAY 0.553191 (-1875 2275);
DISPLAY INVISIBLE (-1875 2275);
FORCEPROP 1 LAST MATERIAL X6S
J 2
(-1516 2304);
DISPLAY 0.574468 (-1516 2304);
PAINT GREEN (-1516 2304);
DISPLAY INVISIBLE (-1516 2304);
FORCEPROP 2 LAST PACK_TYPE C0201
J 2
(-1700 2275);
DISPLAY 0.553191 (-1700 2275);
DISPLAY INVISIBLE (-1700 2275);
FORCEPROP 2 LAST TOLERANCE 20%
J 2
(-1600 2275);
DISPLAY 0.553191 (-1600 2275);
DISPLAY INVISIBLE (-1600 2275);
FORCEPROP 1 LAST PART_NUMBER SP_CH4221MEE01
J 2
(-1641 2313);
DISPLAY 0.574468 (-1641 2313);
PAINT GREEN (-1641 2313);
DISPLAY INVISIBLE (-1641 2313);
FORCEPROP 1 LAST PATH I69
J 2
(-1525 2225);
DISPLAY 0.723404 (-1525 2225);
DISPLAY INVISIBLE (-1525 2225);
FORCEADD Q_CAP_DIFFBUS..2
R 2
(-1375 -550);
FORCEPROP 1 LAST LOCATION C1990
J 2
(-1150 -550);
DISPLAY 0.723404 (-1150 -550);
PAINT GREEN (-1150 -550);
FORCEPROP 0 LAST $SEC 1
J 0
(-1150 -500);
DISPLAY 0.680851 (-1150 -500);
PAINT MONO (-1150 -500);
DISPLAY INVISIBLE (-1150 -500);
FORCEPROP 0 LAST CDS_SEC 1
J 0
(-1150 -500);
DISPLAY 0.680851 (-1150 -500);
DISPLAY INVISIBLE (-1150 -500);
FORCEPROP 0 LASTPIN (-1300 -550) $PN 1
J 0
(-1290 -540);
DISPLAY 0.680851 (-1290 -540);
PAINT MONO (-1290 -540);
FORCEPROP 0 LASTPIN (-1450 -550) $PN 2
J 2
(-1460 -540);
DISPLAY 0.680851 (-1460 -540);
PAINT MONO (-1460 -540);
FORCEPROP 2 LAST VALUE DIFF BUS_0.22UF
J 2
(-1525 -550);
DISPLAY 0.553191 (-1525 -550);
FORCEPROP 1 LAST CDS_LMAN_SYM_OUTLINE -25,50,25,-50
J 2
(-1375 -550);
DISPLAY 0.468085 (-1375 -550);
PAINT GREEN (-1375 -550);
DISPLAY INVISIBLE (-1375 -550);
FORCEPROP 2 LAST CDS_LIB pure_quanta
J 0
(-1375 -550);
DISPLAY INVISIBLE (-1375 -550);
FORCEPROP 2 LAST TOLERANCE 20%
J 2
(-1450 -500);
DISPLAY 0.553191 (-1450 -500);
DISPLAY INVISIBLE (-1450 -500);
FORCEPROP 2 LAST PACK_TYPE C0201
J 2
(-1550 -500);
DISPLAY 0.553191 (-1550 -500);
DISPLAY INVISIBLE (-1550 -500);
FORCEPROP 1 LAST MATERIAL X6S
J 2
(-1366 -471);
DISPLAY 0.574468 (-1366 -471);
PAINT GREEN (-1366 -471);
DISPLAY INVISIBLE (-1366 -471);
FORCEPROP 2 LAST VOLTAGE 6.3V
J 2
(-1725 -500);
DISPLAY 0.553191 (-1725 -500);
DISPLAY INVISIBLE (-1725 -500);
FORCEPROP 1 LAST PIN_NAMES_ROTATE TRUE
J 2
(-1375 -550);
DISPLAY 0.489362 (-1375 -550);
PAINT GREEN (-1375 -550);
DISPLAY INVISIBLE (-1375 -550);
FORCEPROP 1 LAST PART_NUMBER SP_CH4221MEE01
J 2
(-1491 -462);
DISPLAY 0.574468 (-1491 -462);
PAINT GREEN (-1491 -462);
DISPLAY INVISIBLE (-1491 -462);
FORCEPROP 1 LAST PATH I7
J 2
(-1375 -550);
DISPLAY 0.723404 (-1375 -550);
DISPLAY INVISIBLE (-1375 -550);
FORCEADD Q_CAP_DIFFBUS..2
R 2
(-1525 2275);
FORCEPROP 1 LAST LOCATION C1538
J 2
(-1275 2300);
DISPLAY 0.723404 (-1275 2300);
PAINT GREEN (-1275 2300);
FORCEPROP 2 LAST $SEC 1
J 2
(-1350 2350);
DISPLAY 0.680851 (-1350 2350);
PAINT MONO (-1350 2350);
DISPLAY INVISIBLE (-1350 2350);
FORCEPROP 2 LAST CDS_SEC 1
J 2
(-1350 2350);
DISPLAY 0.680851 (-1350 2350);
DISPLAY INVISIBLE (-1350 2350);
FORCEPROP 2 LASTPIN (-1450 2275) $PN 1
J 0
(-1440 2285);
DISPLAY 0.808511 (-1440 2285);
FORCEPROP 2 LASTPIN (-1600 2275) $PN 2
J 2
(-1610 2285);
DISPLAY 0.808511 (-1610 2285);
FORCEPROP 2 LAST VALUE DIFF BUS_0.22UF
J 2
(-1675 2275);
DISPLAY 0.553191 (-1675 2275);
FORCEPROP 1 LAST PIN_NAMES_ROTATE TRUE
J 2
(-1525 2275);
DISPLAY 0.489362 (-1525 2275);
PAINT GREEN (-1525 2275);
DISPLAY INVISIBLE (-1525 2275);
FORCEPROP 2 LAST CDS_LIB pure_quanta
J 2
(-1525 2275);
DISPLAY INVISIBLE (-1525 2275);
FORCEPROP 1 LAST CDS_LMAN_SYM_OUTLINE -25,50,25,-50
J 2
(-1525 2275);
DISPLAY 0.468085 (-1525 2275);
PAINT GREEN (-1525 2275);
DISPLAY INVISIBLE (-1525 2275);
FORCEPROP 2 LAST VOLTAGE 6.3V
J 2
(-1875 2325);
DISPLAY 0.553191 (-1875 2325);
DISPLAY INVISIBLE (-1875 2325);
FORCEPROP 1 LAST MATERIAL X6S
J 2
(-1516 2354);
DISPLAY 0.574468 (-1516 2354);
PAINT GREEN (-1516 2354);
DISPLAY INVISIBLE (-1516 2354);
FORCEPROP 2 LAST PACK_TYPE C0201
J 2
(-1700 2325);
DISPLAY 0.553191 (-1700 2325);
DISPLAY INVISIBLE (-1700 2325);
FORCEPROP 2 LAST TOLERANCE 20%
J 2
(-1600 2325);
DISPLAY 0.553191 (-1600 2325);
DISPLAY INVISIBLE (-1600 2325);
FORCEPROP 1 LAST PART_NUMBER SP_CH4221MEE01
J 2
(-1641 2363);
DISPLAY 0.574468 (-1641 2363);
PAINT GREEN (-1641 2363);
DISPLAY INVISIBLE (-1641 2363);
FORCEPROP 1 LAST PATH I70
J 2
(-1525 2275);
DISPLAY 0.723404 (-1525 2275);
DISPLAY INVISIBLE (-1525 2275);
FORCEADD Q_CAP_DIFFBUS..2
R 2
(-1525 2425);
FORCEPROP 1 LAST LOCATION C1537
J 2
(-1275 2450);
DISPLAY 0.723404 (-1275 2450);
PAINT GREEN (-1275 2450);
FORCEPROP 2 LAST $SEC 1
J 2
(-1350 2500);
DISPLAY 0.680851 (-1350 2500);
PAINT MONO (-1350 2500);
DISPLAY INVISIBLE (-1350 2500);
FORCEPROP 2 LAST CDS_SEC 1
J 2
(-1350 2500);
DISPLAY 0.680851 (-1350 2500);
DISPLAY INVISIBLE (-1350 2500);
FORCEPROP 2 LASTPIN (-1450 2425) $PN 1
J 0
(-1440 2435);
DISPLAY 0.808511 (-1440 2435);
FORCEPROP 2 LASTPIN (-1600 2425) $PN 2
J 2
(-1610 2435);
DISPLAY 0.808511 (-1610 2435);
FORCEPROP 2 LAST VALUE DIFF BUS_0.22UF
J 2
(-1675 2425);
DISPLAY 0.553191 (-1675 2425);
FORCEPROP 1 LAST PIN_NAMES_ROTATE TRUE
J 2
(-1525 2425);
DISPLAY 0.489362 (-1525 2425);
PAINT GREEN (-1525 2425);
DISPLAY INVISIBLE (-1525 2425);
FORCEPROP 2 LAST CDS_LIB pure_quanta
J 2
(-1525 2425);
DISPLAY INVISIBLE (-1525 2425);
FORCEPROP 1 LAST CDS_LMAN_SYM_OUTLINE -25,50,25,-50
J 2
(-1525 2425);
DISPLAY 0.468085 (-1525 2425);
PAINT GREEN (-1525 2425);
DISPLAY INVISIBLE (-1525 2425);
FORCEPROP 2 LAST VOLTAGE 6.3V
J 2
(-1875 2475);
DISPLAY 0.553191 (-1875 2475);
DISPLAY INVISIBLE (-1875 2475);
FORCEPROP 1 LAST MATERIAL X6S
J 2
(-1516 2504);
DISPLAY 0.574468 (-1516 2504);
PAINT GREEN (-1516 2504);
DISPLAY INVISIBLE (-1516 2504);
FORCEPROP 2 LAST PACK_TYPE C0201
J 2
(-1700 2475);
DISPLAY 0.553191 (-1700 2475);
DISPLAY INVISIBLE (-1700 2475);
FORCEPROP 2 LAST TOLERANCE 20%
J 2
(-1600 2475);
DISPLAY 0.553191 (-1600 2475);
DISPLAY INVISIBLE (-1600 2475);
FORCEPROP 1 LAST PART_NUMBER SP_CH4221MEE01
J 2
(-1641 2513);
DISPLAY 0.574468 (-1641 2513);
PAINT GREEN (-1641 2513);
DISPLAY INVISIBLE (-1641 2513);
FORCEPROP 1 LAST PATH I71
J 2
(-1525 2425);
DISPLAY 0.723404 (-1525 2425);
DISPLAY INVISIBLE (-1525 2425);
FORCEADD Q_CAP_DIFFBUS..2
R 2
(-1525 2475);
FORCEPROP 1 LAST LOCATION C1536
J 2
(-1275 2500);
DISPLAY 0.723404 (-1275 2500);
PAINT GREEN (-1275 2500);
FORCEPROP 2 LAST $SEC 1
J 2
(-1350 2550);
DISPLAY 0.680851 (-1350 2550);
PAINT MONO (-1350 2550);
DISPLAY INVISIBLE (-1350 2550);
FORCEPROP 2 LAST CDS_SEC 1
J 2
(-1350 2550);
DISPLAY 0.680851 (-1350 2550);
DISPLAY INVISIBLE (-1350 2550);
FORCEPROP 2 LASTPIN (-1450 2475) $PN 1
J 0
(-1440 2485);
DISPLAY 0.808511 (-1440 2485);
FORCEPROP 2 LASTPIN (-1600 2475) $PN 2
J 2
(-1610 2485);
DISPLAY 0.808511 (-1610 2485);
FORCEPROP 2 LAST VALUE DIFF BUS_0.22UF
J 2
(-1675 2475);
DISPLAY 0.553191 (-1675 2475);
FORCEPROP 1 LAST PIN_NAMES_ROTATE TRUE
J 2
(-1525 2475);
DISPLAY 0.489362 (-1525 2475);
PAINT GREEN (-1525 2475);
DISPLAY INVISIBLE (-1525 2475);
FORCEPROP 2 LAST CDS_LIB pure_quanta
J 2
(-1525 2475);
DISPLAY INVISIBLE (-1525 2475);
FORCEPROP 1 LAST CDS_LMAN_SYM_OUTLINE -25,50,25,-50
J 2
(-1525 2475);
DISPLAY 0.468085 (-1525 2475);
PAINT GREEN (-1525 2475);
DISPLAY INVISIBLE (-1525 2475);
FORCEPROP 2 LAST VOLTAGE 6.3V
J 2
(-1875 2525);
DISPLAY 0.553191 (-1875 2525);
DISPLAY INVISIBLE (-1875 2525);
FORCEPROP 1 LAST MATERIAL X6S
J 2
(-1516 2554);
DISPLAY 0.574468 (-1516 2554);
PAINT GREEN (-1516 2554);
DISPLAY INVISIBLE (-1516 2554);
FORCEPROP 2 LAST PACK_TYPE C0201
J 2
(-1700 2525);
DISPLAY 0.553191 (-1700 2525);
DISPLAY INVISIBLE (-1700 2525);
FORCEPROP 2 LAST TOLERANCE 20%
J 2
(-1600 2525);
DISPLAY 0.553191 (-1600 2525);
DISPLAY INVISIBLE (-1600 2525);
FORCEPROP 1 LAST PART_NUMBER SP_CH4221MEE01
J 2
(-1641 2563);
DISPLAY 0.574468 (-1641 2563);
PAINT GREEN (-1641 2563);
DISPLAY INVISIBLE (-1641 2563);
FORCEPROP 1 LAST PATH I72
J 2
(-1525 2475);
DISPLAY 0.723404 (-1525 2475);
DISPLAY INVISIBLE (-1525 2475);
FORCEADD Q_CAP_DIFFBUS..2
R 2
(-1525 2625);
FORCEPROP 1 LAST LOCATION C1535
J 2
(-1275 2650);
DISPLAY 0.723404 (-1275 2650);
PAINT GREEN (-1275 2650);
FORCEPROP 2 LAST $SEC 1
J 2
(-1350 2700);
DISPLAY 0.680851 (-1350 2700);
PAINT MONO (-1350 2700);
DISPLAY INVISIBLE (-1350 2700);
FORCEPROP 2 LAST CDS_SEC 1
J 2
(-1350 2700);
DISPLAY 0.680851 (-1350 2700);
DISPLAY INVISIBLE (-1350 2700);
FORCEPROP 2 LASTPIN (-1450 2625) $PN 1
J 0
(-1440 2635);
DISPLAY 0.808511 (-1440 2635);
FORCEPROP 2 LASTPIN (-1600 2625) $PN 2
J 2
(-1610 2635);
DISPLAY 0.808511 (-1610 2635);
FORCEPROP 2 LAST VALUE DIFF BUS_0.22UF
J 2
(-1675 2625);
DISPLAY 0.553191 (-1675 2625);
FORCEPROP 1 LAST PIN_NAMES_ROTATE TRUE
J 2
(-1525 2625);
DISPLAY 0.489362 (-1525 2625);
PAINT GREEN (-1525 2625);
DISPLAY INVISIBLE (-1525 2625);
FORCEPROP 2 LAST CDS_LIB pure_quanta
J 2
(-1525 2625);
DISPLAY INVISIBLE (-1525 2625);
FORCEPROP 1 LAST CDS_LMAN_SYM_OUTLINE -25,50,25,-50
J 2
(-1525 2625);
DISPLAY 0.468085 (-1525 2625);
PAINT GREEN (-1525 2625);
DISPLAY INVISIBLE (-1525 2625);
FORCEPROP 2 LAST VOLTAGE 6.3V
J 2
(-1875 2675);
DISPLAY 0.553191 (-1875 2675);
DISPLAY INVISIBLE (-1875 2675);
FORCEPROP 1 LAST MATERIAL X6S
J 2
(-1516 2704);
DISPLAY 0.574468 (-1516 2704);
PAINT GREEN (-1516 2704);
DISPLAY INVISIBLE (-1516 2704);
FORCEPROP 2 LAST PACK_TYPE C0201
J 2
(-1700 2675);
DISPLAY 0.553191 (-1700 2675);
DISPLAY INVISIBLE (-1700 2675);
FORCEPROP 2 LAST TOLERANCE 20%
J 2
(-1600 2675);
DISPLAY 0.553191 (-1600 2675);
DISPLAY INVISIBLE (-1600 2675);
FORCEPROP 1 LAST PART_NUMBER SP_CH4221MEE01
J 2
(-1641 2713);
DISPLAY 0.574468 (-1641 2713);
PAINT GREEN (-1641 2713);
DISPLAY INVISIBLE (-1641 2713);
FORCEPROP 1 LAST PATH I73
J 2
(-1525 2625);
DISPLAY 0.723404 (-1525 2625);
DISPLAY INVISIBLE (-1525 2625);
FORCEADD Q_CAP_DIFFBUS..2
R 2
(-1525 2675);
FORCEPROP 1 LAST LOCATION C1534
J 2
(-1275 2700);
DISPLAY 0.723404 (-1275 2700);
PAINT GREEN (-1275 2700);
FORCEPROP 2 LAST $SEC 1
J 2
(-1350 2750);
DISPLAY 0.680851 (-1350 2750);
PAINT MONO (-1350 2750);
DISPLAY INVISIBLE (-1350 2750);
FORCEPROP 2 LAST CDS_SEC 1
J 2
(-1350 2750);
DISPLAY 0.680851 (-1350 2750);
DISPLAY INVISIBLE (-1350 2750);
FORCEPROP 2 LASTPIN (-1450 2675) $PN 1
J 0
(-1440 2685);
DISPLAY 0.808511 (-1440 2685);
FORCEPROP 2 LASTPIN (-1600 2675) $PN 2
J 2
(-1610 2685);
DISPLAY 0.808511 (-1610 2685);
FORCEPROP 2 LAST VALUE DIFF BUS_0.22UF
J 2
(-1675 2675);
DISPLAY 0.553191 (-1675 2675);
FORCEPROP 1 LAST PIN_NAMES_ROTATE TRUE
J 2
(-1525 2675);
DISPLAY 0.489362 (-1525 2675);
PAINT GREEN (-1525 2675);
DISPLAY INVISIBLE (-1525 2675);
FORCEPROP 2 LAST CDS_LIB pure_quanta
J 2
(-1525 2675);
DISPLAY INVISIBLE (-1525 2675);
FORCEPROP 1 LAST CDS_LMAN_SYM_OUTLINE -25,50,25,-50
J 2
(-1525 2675);
DISPLAY 0.468085 (-1525 2675);
PAINT GREEN (-1525 2675);
DISPLAY INVISIBLE (-1525 2675);
FORCEPROP 2 LAST VOLTAGE 6.3V
J 2
(-1875 2725);
DISPLAY 0.553191 (-1875 2725);
DISPLAY INVISIBLE (-1875 2725);
FORCEPROP 1 LAST MATERIAL X6S
J 2
(-1516 2754);
DISPLAY 0.574468 (-1516 2754);
PAINT GREEN (-1516 2754);
DISPLAY INVISIBLE (-1516 2754);
FORCEPROP 2 LAST PACK_TYPE C0201
J 2
(-1700 2725);
DISPLAY 0.553191 (-1700 2725);
DISPLAY INVISIBLE (-1700 2725);
FORCEPROP 2 LAST TOLERANCE 20%
J 2
(-1600 2725);
DISPLAY 0.553191 (-1600 2725);
DISPLAY INVISIBLE (-1600 2725);
FORCEPROP 1 LAST PART_NUMBER SP_CH4221MEE01
J 2
(-1641 2763);
DISPLAY 0.574468 (-1641 2763);
PAINT GREEN (-1641 2763);
DISPLAY INVISIBLE (-1641 2763);
FORCEPROP 1 LAST PATH I74
J 2
(-1525 2675);
DISPLAY 0.723404 (-1525 2675);
DISPLAY INVISIBLE (-1525 2675);
FORCEADD Q_CAP_DIFFBUS..2
R 2
(-1525 2825);
FORCEPROP 1 LAST LOCATION C1533
J 2
(-1275 2850);
DISPLAY 0.723404 (-1275 2850);
PAINT GREEN (-1275 2850);
FORCEPROP 2 LAST $SEC 1
J 2
(-1350 2900);
DISPLAY 0.680851 (-1350 2900);
PAINT MONO (-1350 2900);
DISPLAY INVISIBLE (-1350 2900);
FORCEPROP 2 LAST CDS_SEC 1
J 2
(-1350 2900);
DISPLAY 0.680851 (-1350 2900);
DISPLAY INVISIBLE (-1350 2900);
FORCEPROP 2 LASTPIN (-1450 2825) $PN 1
J 0
(-1440 2835);
DISPLAY 0.808511 (-1440 2835);
FORCEPROP 2 LASTPIN (-1600 2825) $PN 2
J 2
(-1610 2835);
DISPLAY 0.808511 (-1610 2835);
FORCEPROP 2 LAST VALUE DIFF BUS_0.22UF
J 2
(-1675 2825);
DISPLAY 0.553191 (-1675 2825);
FORCEPROP 1 LAST PIN_NAMES_ROTATE TRUE
J 2
(-1525 2825);
DISPLAY 0.489362 (-1525 2825);
PAINT GREEN (-1525 2825);
DISPLAY INVISIBLE (-1525 2825);
FORCEPROP 2 LAST CDS_LIB pure_quanta
J 2
(-1525 2825);
DISPLAY INVISIBLE (-1525 2825);
FORCEPROP 1 LAST CDS_LMAN_SYM_OUTLINE -25,50,25,-50
J 2
(-1525 2825);
DISPLAY 0.468085 (-1525 2825);
PAINT GREEN (-1525 2825);
DISPLAY INVISIBLE (-1525 2825);
FORCEPROP 2 LAST VOLTAGE 6.3V
J 2
(-1875 2875);
DISPLAY 0.553191 (-1875 2875);
DISPLAY INVISIBLE (-1875 2875);
FORCEPROP 1 LAST MATERIAL X6S
J 2
(-1516 2904);
DISPLAY 0.574468 (-1516 2904);
PAINT GREEN (-1516 2904);
DISPLAY INVISIBLE (-1516 2904);
FORCEPROP 2 LAST PACK_TYPE C0201
J 2
(-1700 2875);
DISPLAY 0.553191 (-1700 2875);
DISPLAY INVISIBLE (-1700 2875);
FORCEPROP 2 LAST TOLERANCE 20%
J 2
(-1600 2875);
DISPLAY 0.553191 (-1600 2875);
DISPLAY INVISIBLE (-1600 2875);
FORCEPROP 1 LAST PART_NUMBER SP_CH4221MEE01
J 2
(-1641 2913);
DISPLAY 0.574468 (-1641 2913);
PAINT GREEN (-1641 2913);
DISPLAY INVISIBLE (-1641 2913);
FORCEPROP 1 LAST PATH I75
J 2
(-1525 2825);
DISPLAY 0.723404 (-1525 2825);
DISPLAY INVISIBLE (-1525 2825);
FORCEADD Q_CAP_DIFFBUS..2
R 2
(-1525 2875);
FORCEPROP 1 LAST LOCATION C1532
J 2
(-1275 2900);
DISPLAY 0.723404 (-1275 2900);
PAINT GREEN (-1275 2900);
FORCEPROP 2 LAST $SEC 1
J 2
(-1350 2950);
DISPLAY 0.680851 (-1350 2950);
PAINT MONO (-1350 2950);
DISPLAY INVISIBLE (-1350 2950);
FORCEPROP 2 LAST CDS_SEC 1
J 2
(-1350 2950);
DISPLAY 0.680851 (-1350 2950);
DISPLAY INVISIBLE (-1350 2950);
FORCEPROP 2 LASTPIN (-1450 2875) $PN 1
J 0
(-1440 2885);
DISPLAY 0.808511 (-1440 2885);
FORCEPROP 2 LASTPIN (-1600 2875) $PN 2
J 2
(-1610 2885);
DISPLAY 0.808511 (-1610 2885);
FORCEPROP 2 LAST VALUE DIFF BUS_0.22UF
J 2
(-1675 2875);
DISPLAY 0.553191 (-1675 2875);
FORCEPROP 1 LAST PIN_NAMES_ROTATE TRUE
J 2
(-1525 2875);
DISPLAY 0.489362 (-1525 2875);
PAINT GREEN (-1525 2875);
DISPLAY INVISIBLE (-1525 2875);
FORCEPROP 1 LAST CDS_LMAN_SYM_OUTLINE -25,50,25,-50
J 2
(-1525 2875);
DISPLAY 0.468085 (-1525 2875);
PAINT GREEN (-1525 2875);
DISPLAY INVISIBLE (-1525 2875);
FORCEPROP 2 LAST CDS_LIB pure_quanta
J 2
(-1525 2875);
DISPLAY INVISIBLE (-1525 2875);
FORCEPROP 2 LAST VOLTAGE 6.3V
J 2
(-1875 2925);
DISPLAY 0.553191 (-1875 2925);
DISPLAY INVISIBLE (-1875 2925);
FORCEPROP 1 LAST MATERIAL X6S
J 2
(-1516 2954);
DISPLAY 0.574468 (-1516 2954);
PAINT GREEN (-1516 2954);
DISPLAY INVISIBLE (-1516 2954);
FORCEPROP 2 LAST PACK_TYPE C0201
J 2
(-1700 2925);
DISPLAY 0.553191 (-1700 2925);
DISPLAY INVISIBLE (-1700 2925);
FORCEPROP 2 LAST TOLERANCE 20%
J 2
(-1600 2925);
DISPLAY 0.553191 (-1600 2925);
DISPLAY INVISIBLE (-1600 2925);
FORCEPROP 1 LAST PART_NUMBER SP_CH4221MEE01
J 2
(-1641 2963);
DISPLAY 0.574468 (-1641 2963);
PAINT GREEN (-1641 2963);
DISPLAY INVISIBLE (-1641 2963);
FORCEPROP 1 LAST PATH I76
J 2
(-1525 2875);
DISPLAY 0.723404 (-1525 2875);
DISPLAY INVISIBLE (-1525 2875);
FORCEADD Q_CAP_DIFFBUS..2
R 2
(-1500 3050);
FORCEPROP 1 LAST LOCATION C1531
J 2
(-1250 3075);
DISPLAY 0.723404 (-1250 3075);
PAINT GREEN (-1250 3075);
FORCEPROP 2 LAST $SEC 1
J 2
(-1325 3125);
DISPLAY 0.680851 (-1325 3125);
PAINT MONO (-1325 3125);
DISPLAY INVISIBLE (-1325 3125);
FORCEPROP 2 LAST CDS_SEC 1
J 2
(-1325 3125);
DISPLAY 0.680851 (-1325 3125);
DISPLAY INVISIBLE (-1325 3125);
FORCEPROP 2 LASTPIN (-1425 3050) $PN 1
J 0
(-1415 3060);
DISPLAY 0.808511 (-1415 3060);
FORCEPROP 2 LASTPIN (-1575 3050) $PN 2
J 2
(-1585 3060);
DISPLAY 0.808511 (-1585 3060);
FORCEPROP 2 LAST VALUE DIFF BUS_0.22UF
J 2
(-1650 3050);
DISPLAY 0.553191 (-1650 3050);
FORCEPROP 1 LAST PIN_NAMES_ROTATE TRUE
J 2
(-1500 3050);
DISPLAY 0.489362 (-1500 3050);
PAINT GREEN (-1500 3050);
DISPLAY INVISIBLE (-1500 3050);
FORCEPROP 2 LAST VOLTAGE 6.3V
J 2
(-1850 3100);
DISPLAY 0.553191 (-1850 3100);
DISPLAY INVISIBLE (-1850 3100);
FORCEPROP 1 LAST MATERIAL X6S
J 2
(-1491 3129);
DISPLAY 0.574468 (-1491 3129);
PAINT GREEN (-1491 3129);
DISPLAY INVISIBLE (-1491 3129);
FORCEPROP 2 LAST PACK_TYPE C0201
J 2
(-1675 3100);
DISPLAY 0.553191 (-1675 3100);
DISPLAY INVISIBLE (-1675 3100);
FORCEPROP 2 LAST TOLERANCE 20%
J 2
(-1575 3100);
DISPLAY 0.553191 (-1575 3100);
DISPLAY INVISIBLE (-1575 3100);
FORCEPROP 1 LAST CDS_LMAN_SYM_OUTLINE -25,50,25,-50
J 2
(-1500 3050);
DISPLAY 0.468085 (-1500 3050);
PAINT GREEN (-1500 3050);
DISPLAY INVISIBLE (-1500 3050);
FORCEPROP 2 LAST CDS_LIB pure_quanta
J 2
(-1500 3050);
DISPLAY INVISIBLE (-1500 3050);
FORCEPROP 1 LAST PART_NUMBER SP_CH4221MEE01
J 2
(-1616 3138);
DISPLAY 0.574468 (-1616 3138);
PAINT GREEN (-1616 3138);
DISPLAY INVISIBLE (-1616 3138);
FORCEPROP 1 LAST PATH I77
J 2
(-1500 3050);
DISPLAY 0.723404 (-1500 3050);
DISPLAY INVISIBLE (-1500 3050);
FORCEADD Q_CAP_DIFFBUS..2
R 2
(-1500 3100);
FORCEPROP 1 LAST LOCATION C1530
J 2
(-1250 3125);
DISPLAY 0.723404 (-1250 3125);
PAINT GREEN (-1250 3125);
FORCEPROP 2 LAST $SEC 1
J 2
(-1325 3175);
DISPLAY 0.680851 (-1325 3175);
PAINT MONO (-1325 3175);
DISPLAY INVISIBLE (-1325 3175);
FORCEPROP 2 LAST CDS_SEC 1
J 2
(-1325 3175);
DISPLAY 0.680851 (-1325 3175);
DISPLAY INVISIBLE (-1325 3175);
FORCEPROP 2 LASTPIN (-1425 3100) $PN 1
J 0
(-1415 3110);
DISPLAY 0.808511 (-1415 3110);
FORCEPROP 2 LASTPIN (-1575 3100) $PN 2
J 2
(-1585 3110);
DISPLAY 0.808511 (-1585 3110);
FORCEPROP 2 LAST VALUE DIFF BUS_0.22UF
J 2
(-1650 3100);
DISPLAY 0.553191 (-1650 3100);
FORCEPROP 1 LAST PIN_NAMES_ROTATE TRUE
J 2
(-1500 3100);
DISPLAY 0.489362 (-1500 3100);
PAINT GREEN (-1500 3100);
DISPLAY INVISIBLE (-1500 3100);
FORCEPROP 2 LAST VOLTAGE 6.3V
J 2
(-1850 3150);
DISPLAY 0.553191 (-1850 3150);
DISPLAY INVISIBLE (-1850 3150);
FORCEPROP 1 LAST MATERIAL X6S
J 2
(-1491 3179);
DISPLAY 0.574468 (-1491 3179);
PAINT GREEN (-1491 3179);
DISPLAY INVISIBLE (-1491 3179);
FORCEPROP 2 LAST PACK_TYPE C0201
J 2
(-1675 3150);
DISPLAY 0.553191 (-1675 3150);
DISPLAY INVISIBLE (-1675 3150);
FORCEPROP 2 LAST TOLERANCE 20%
J 2
(-1575 3150);
DISPLAY 0.553191 (-1575 3150);
DISPLAY INVISIBLE (-1575 3150);
FORCEPROP 1 LAST CDS_LMAN_SYM_OUTLINE -25,50,25,-50
J 2
(-1500 3100);
DISPLAY 0.468085 (-1500 3100);
PAINT GREEN (-1500 3100);
DISPLAY INVISIBLE (-1500 3100);
FORCEPROP 2 LAST CDS_LIB pure_quanta
J 2
(-1500 3100);
DISPLAY INVISIBLE (-1500 3100);
FORCEPROP 1 LAST PART_NUMBER SP_CH4221MEE01
J 2
(-1616 3188);
DISPLAY 0.574468 (-1616 3188);
PAINT GREEN (-1616 3188);
DISPLAY INVISIBLE (-1616 3188);
FORCEPROP 1 LAST PATH I78
J 2
(-1500 3100);
DISPLAY 0.723404 (-1500 3100);
DISPLAY INVISIBLE (-1500 3100);
FORCEADD Q_CAP_DIFFBUS..2
R 2
(-1500 3250);
FORCEPROP 1 LAST LOCATION C1529
J 2
(-1250 3275);
DISPLAY 0.723404 (-1250 3275);
PAINT GREEN (-1250 3275);
FORCEPROP 2 LAST $SEC 1
J 2
(-1325 3325);
DISPLAY 0.680851 (-1325 3325);
PAINT MONO (-1325 3325);
DISPLAY INVISIBLE (-1325 3325);
FORCEPROP 2 LAST CDS_SEC 1
J 2
(-1325 3325);
DISPLAY 0.680851 (-1325 3325);
DISPLAY INVISIBLE (-1325 3325);
FORCEPROP 2 LASTPIN (-1425 3250) $PN 1
J 0
(-1415 3260);
DISPLAY 0.808511 (-1415 3260);
FORCEPROP 2 LASTPIN (-1575 3250) $PN 2
J 2
(-1585 3260);
DISPLAY 0.808511 (-1585 3260);
FORCEPROP 2 LAST VALUE DIFF BUS_0.22UF
J 2
(-1650 3250);
DISPLAY 0.553191 (-1650 3250);
FORCEPROP 1 LAST PIN_NAMES_ROTATE TRUE
J 2
(-1500 3250);
DISPLAY 0.489362 (-1500 3250);
PAINT GREEN (-1500 3250);
DISPLAY INVISIBLE (-1500 3250);
FORCEPROP 2 LAST VOLTAGE 6.3V
J 2
(-1850 3300);
DISPLAY 0.553191 (-1850 3300);
DISPLAY INVISIBLE (-1850 3300);
FORCEPROP 1 LAST MATERIAL X6S
J 2
(-1491 3329);
DISPLAY 0.574468 (-1491 3329);
PAINT GREEN (-1491 3329);
DISPLAY INVISIBLE (-1491 3329);
FORCEPROP 2 LAST PACK_TYPE C0201
J 2
(-1675 3300);
DISPLAY 0.553191 (-1675 3300);
DISPLAY INVISIBLE (-1675 3300);
FORCEPROP 2 LAST TOLERANCE 20%
J 2
(-1575 3300);
DISPLAY 0.553191 (-1575 3300);
DISPLAY INVISIBLE (-1575 3300);
FORCEPROP 1 LAST CDS_LMAN_SYM_OUTLINE -25,50,25,-50
J 2
(-1500 3250);
DISPLAY 0.468085 (-1500 3250);
PAINT GREEN (-1500 3250);
DISPLAY INVISIBLE (-1500 3250);
FORCEPROP 2 LAST CDS_LIB pure_quanta
J 2
(-1500 3250);
DISPLAY INVISIBLE (-1500 3250);
FORCEPROP 1 LAST PART_NUMBER SP_CH4221MEE01
J 2
(-1616 3338);
DISPLAY 0.574468 (-1616 3338);
PAINT GREEN (-1616 3338);
DISPLAY INVISIBLE (-1616 3338);
FORCEPROP 1 LAST PATH I79
J 2
(-1500 3250);
DISPLAY 0.723404 (-1500 3250);
DISPLAY INVISIBLE (-1500 3250);
FORCEADD Q_CAP_DIFFBUS..2
R 2
(-1375 -500);
FORCEPROP 1 LAST LOCATION C1989
J 2
(-1150 -500);
DISPLAY 0.723404 (-1150 -500);
PAINT GREEN (-1150 -500);
FORCEPROP 0 LAST $SEC 1
J 0
(-1150 -450);
DISPLAY 0.680851 (-1150 -450);
PAINT MONO (-1150 -450);
DISPLAY INVISIBLE (-1150 -450);
FORCEPROP 0 LAST CDS_SEC 1
J 0
(-1150 -450);
DISPLAY 0.680851 (-1150 -450);
DISPLAY INVISIBLE (-1150 -450);
FORCEPROP 0 LASTPIN (-1300 -500) $PN 1
J 0
(-1290 -490);
DISPLAY 0.680851 (-1290 -490);
PAINT MONO (-1290 -490);
FORCEPROP 0 LASTPIN (-1450 -500) $PN 2
J 2
(-1460 -490);
DISPLAY 0.680851 (-1460 -490);
PAINT MONO (-1460 -490);
FORCEPROP 2 LAST VALUE DIFF BUS_0.22UF
J 2
(-1525 -500);
DISPLAY 0.553191 (-1525 -500);
FORCEPROP 2 LAST CDS_LIB pure_quanta
J 0
(-1375 -500);
DISPLAY INVISIBLE (-1375 -500);
FORCEPROP 1 LAST CDS_LMAN_SYM_OUTLINE -25,50,25,-50
J 2
(-1375 -500);
DISPLAY 0.468085 (-1375 -500);
PAINT GREEN (-1375 -500);
DISPLAY INVISIBLE (-1375 -500);
FORCEPROP 1 LAST PIN_NAMES_ROTATE TRUE
J 2
(-1375 -500);
DISPLAY 0.489362 (-1375 -500);
PAINT GREEN (-1375 -500);
DISPLAY INVISIBLE (-1375 -500);
FORCEPROP 2 LAST VOLTAGE 6.3V
J 2
(-1725 -450);
DISPLAY 0.553191 (-1725 -450);
DISPLAY INVISIBLE (-1725 -450);
FORCEPROP 1 LAST MATERIAL X6S
J 2
(-1366 -421);
DISPLAY 0.574468 (-1366 -421);
PAINT GREEN (-1366 -421);
DISPLAY INVISIBLE (-1366 -421);
FORCEPROP 2 LAST PACK_TYPE C0201
J 2
(-1550 -450);
DISPLAY 0.553191 (-1550 -450);
DISPLAY INVISIBLE (-1550 -450);
FORCEPROP 2 LAST TOLERANCE 20%
J 2
(-1450 -450);
DISPLAY 0.553191 (-1450 -450);
DISPLAY INVISIBLE (-1450 -450);
FORCEPROP 1 LAST PART_NUMBER SP_CH4221MEE01
J 2
(-1491 -412);
DISPLAY 0.574468 (-1491 -412);
PAINT GREEN (-1491 -412);
DISPLAY INVISIBLE (-1491 -412);
FORCEPROP 1 LAST PATH I8
J 2
(-1375 -500);
DISPLAY 0.723404 (-1375 -500);
DISPLAY INVISIBLE (-1375 -500);
FORCEADD Q_CAP_DIFFBUS..2
R 2
(-1500 3300);
FORCEPROP 1 LAST LOCATION C1528
J 2
(-1250 3325);
DISPLAY 0.723404 (-1250 3325);
PAINT GREEN (-1250 3325);
FORCEPROP 2 LAST $SEC 1
J 2
(-1325 3375);
DISPLAY 0.680851 (-1325 3375);
PAINT MONO (-1325 3375);
DISPLAY INVISIBLE (-1325 3375);
FORCEPROP 2 LAST CDS_SEC 1
J 2
(-1325 3375);
DISPLAY 0.680851 (-1325 3375);
DISPLAY INVISIBLE (-1325 3375);
FORCEPROP 2 LASTPIN (-1425 3300) $PN 1
J 0
(-1415 3310);
DISPLAY 0.808511 (-1415 3310);
FORCEPROP 2 LASTPIN (-1575 3300) $PN 2
J 2
(-1585 3310);
DISPLAY 0.808511 (-1585 3310);
FORCEPROP 2 LAST VALUE DIFF BUS_0.22UF
J 2
(-1650 3300);
DISPLAY 0.553191 (-1650 3300);
FORCEPROP 1 LAST PIN_NAMES_ROTATE TRUE
J 2
(-1500 3300);
DISPLAY 0.489362 (-1500 3300);
PAINT GREEN (-1500 3300);
DISPLAY INVISIBLE (-1500 3300);
FORCEPROP 2 LAST VOLTAGE 6.3V
J 2
(-1850 3350);
DISPLAY 0.553191 (-1850 3350);
DISPLAY INVISIBLE (-1850 3350);
FORCEPROP 1 LAST MATERIAL X6S
J 2
(-1491 3379);
DISPLAY 0.574468 (-1491 3379);
PAINT GREEN (-1491 3379);
DISPLAY INVISIBLE (-1491 3379);
FORCEPROP 2 LAST PACK_TYPE C0201
J 2
(-1675 3350);
DISPLAY 0.553191 (-1675 3350);
DISPLAY INVISIBLE (-1675 3350);
FORCEPROP 2 LAST TOLERANCE 20%
J 2
(-1575 3350);
DISPLAY 0.553191 (-1575 3350);
DISPLAY INVISIBLE (-1575 3350);
FORCEPROP 2 LAST CDS_LIB pure_quanta
J 2
(-1500 3300);
DISPLAY INVISIBLE (-1500 3300);
FORCEPROP 1 LAST CDS_LMAN_SYM_OUTLINE -25,50,25,-50
J 2
(-1500 3300);
DISPLAY 0.468085 (-1500 3300);
PAINT GREEN (-1500 3300);
DISPLAY INVISIBLE (-1500 3300);
FORCEPROP 1 LAST PART_NUMBER SP_CH4221MEE01
J 2
(-1616 3388);
DISPLAY 0.574468 (-1616 3388);
PAINT GREEN (-1616 3388);
DISPLAY INVISIBLE (-1616 3388);
FORCEPROP 1 LAST PATH I80
J 2
(-1500 3300);
DISPLAY 0.723404 (-1500 3300);
DISPLAY INVISIBLE (-1500 3300);
FORCEADD Q_CAP_DIFFBUS..2
R 2
(-1500 3500);
FORCEPROP 1 LAST LOCATION C1526
J 2
(-1250 3525);
DISPLAY 0.723404 (-1250 3525);
PAINT GREEN (-1250 3525);
FORCEPROP 2 LAST $SEC 1
J 2
(-1325 3575);
DISPLAY 0.680851 (-1325 3575);
PAINT MONO (-1325 3575);
DISPLAY INVISIBLE (-1325 3575);
FORCEPROP 2 LAST CDS_SEC 1
J 2
(-1325 3575);
DISPLAY 0.680851 (-1325 3575);
DISPLAY INVISIBLE (-1325 3575);
FORCEPROP 2 LASTPIN (-1425 3500) $PN 1
J 0
(-1415 3510);
DISPLAY 0.808511 (-1415 3510);
FORCEPROP 2 LASTPIN (-1575 3500) $PN 2
J 2
(-1585 3510);
DISPLAY 0.808511 (-1585 3510);
FORCEPROP 2 LAST VALUE DIFF BUS_0.22UF
J 2
(-1650 3500);
DISPLAY 0.553191 (-1650 3500);
FORCEPROP 1 LAST PIN_NAMES_ROTATE TRUE
J 2
(-1500 3500);
DISPLAY 0.489362 (-1500 3500);
PAINT GREEN (-1500 3500);
DISPLAY INVISIBLE (-1500 3500);
FORCEPROP 2 LAST VOLTAGE 6.3V
J 2
(-1850 3550);
DISPLAY 0.553191 (-1850 3550);
DISPLAY INVISIBLE (-1850 3550);
FORCEPROP 1 LAST MATERIAL X6S
J 2
(-1491 3579);
DISPLAY 0.574468 (-1491 3579);
PAINT GREEN (-1491 3579);
DISPLAY INVISIBLE (-1491 3579);
FORCEPROP 2 LAST PACK_TYPE C0201
J 2
(-1675 3550);
DISPLAY 0.553191 (-1675 3550);
DISPLAY INVISIBLE (-1675 3550);
FORCEPROP 2 LAST TOLERANCE 20%
J 2
(-1575 3550);
DISPLAY 0.553191 (-1575 3550);
DISPLAY INVISIBLE (-1575 3550);
FORCEPROP 1 LAST CDS_LMAN_SYM_OUTLINE -25,50,25,-50
J 2
(-1500 3500);
DISPLAY 0.468085 (-1500 3500);
PAINT GREEN (-1500 3500);
DISPLAY INVISIBLE (-1500 3500);
FORCEPROP 2 LAST CDS_LIB pure_quanta
J 2
(-1500 3500);
DISPLAY INVISIBLE (-1500 3500);
FORCEPROP 1 LAST PART_NUMBER SP_CH4221MEE01
J 2
(-1616 3588);
DISPLAY 0.574468 (-1616 3588);
PAINT GREEN (-1616 3588);
DISPLAY INVISIBLE (-1616 3588);
FORCEPROP 1 LAST PATH I81
J 2
(-1500 3500);
DISPLAY 0.723404 (-1500 3500);
DISPLAY INVISIBLE (-1500 3500);
FORCEADD Q_CAP_DIFFBUS..2
R 2
(-1500 3450);
FORCEPROP 1 LAST LOCATION C1527
J 2
(-1250 3475);
DISPLAY 0.723404 (-1250 3475);
PAINT GREEN (-1250 3475);
FORCEPROP 2 LAST $SEC 1
J 2
(-1325 3525);
DISPLAY 0.680851 (-1325 3525);
PAINT MONO (-1325 3525);
DISPLAY INVISIBLE (-1325 3525);
FORCEPROP 2 LAST CDS_SEC 1
J 2
(-1325 3525);
DISPLAY 0.680851 (-1325 3525);
DISPLAY INVISIBLE (-1325 3525);
FORCEPROP 2 LASTPIN (-1425 3450) $PN 1
J 0
(-1415 3460);
DISPLAY 0.808511 (-1415 3460);
FORCEPROP 2 LASTPIN (-1575 3450) $PN 2
J 2
(-1585 3460);
DISPLAY 0.808511 (-1585 3460);
FORCEPROP 2 LAST VALUE DIFF BUS_0.22UF
J 2
(-1650 3450);
DISPLAY 0.553191 (-1650 3450);
FORCEPROP 1 LAST PIN_NAMES_ROTATE TRUE
J 2
(-1500 3450);
DISPLAY 0.489362 (-1500 3450);
PAINT GREEN (-1500 3450);
DISPLAY INVISIBLE (-1500 3450);
FORCEPROP 2 LAST VOLTAGE 6.3V
J 2
(-1850 3500);
DISPLAY 0.553191 (-1850 3500);
DISPLAY INVISIBLE (-1850 3500);
FORCEPROP 1 LAST MATERIAL X6S
J 2
(-1491 3529);
DISPLAY 0.574468 (-1491 3529);
PAINT GREEN (-1491 3529);
DISPLAY INVISIBLE (-1491 3529);
FORCEPROP 2 LAST PACK_TYPE C0201
J 2
(-1675 3500);
DISPLAY 0.553191 (-1675 3500);
DISPLAY INVISIBLE (-1675 3500);
FORCEPROP 2 LAST TOLERANCE 20%
J 2
(-1575 3500);
DISPLAY 0.553191 (-1575 3500);
DISPLAY INVISIBLE (-1575 3500);
FORCEPROP 1 LAST CDS_LMAN_SYM_OUTLINE -25,50,25,-50
J 2
(-1500 3450);
DISPLAY 0.468085 (-1500 3450);
PAINT GREEN (-1500 3450);
DISPLAY INVISIBLE (-1500 3450);
FORCEPROP 2 LAST CDS_LIB pure_quanta
J 2
(-1500 3450);
DISPLAY INVISIBLE (-1500 3450);
FORCEPROP 1 LAST PART_NUMBER SP_CH4221MEE01
J 2
(-1616 3538);
DISPLAY 0.574468 (-1616 3538);
PAINT GREEN (-1616 3538);
DISPLAY INVISIBLE (-1616 3538);
FORCEPROP 1 LAST PATH I82
J 2
(-1500 3450);
DISPLAY 0.723404 (-1500 3450);
DISPLAY INVISIBLE (-1500 3450);
FORCEADD Q_CAP_DIFFBUS..2
R 2
(-1500 3650);
FORCEPROP 1 LAST LOCATION C1525
J 2
(-1250 3675);
DISPLAY 0.723404 (-1250 3675);
PAINT GREEN (-1250 3675);
FORCEPROP 2 LAST $SEC 1
J 2
(-1325 3725);
DISPLAY 0.680851 (-1325 3725);
PAINT MONO (-1325 3725);
DISPLAY INVISIBLE (-1325 3725);
FORCEPROP 2 LAST CDS_SEC 1
J 2
(-1325 3725);
DISPLAY 0.680851 (-1325 3725);
DISPLAY INVISIBLE (-1325 3725);
FORCEPROP 2 LASTPIN (-1425 3650) $PN 1
J 0
(-1415 3660);
DISPLAY 0.808511 (-1415 3660);
FORCEPROP 2 LASTPIN (-1575 3650) $PN 2
J 2
(-1585 3660);
DISPLAY 0.808511 (-1585 3660);
FORCEPROP 2 LAST VALUE DIFF BUS_0.22UF
J 2
(-1650 3650);
DISPLAY 0.553191 (-1650 3650);
FORCEPROP 1 LAST PIN_NAMES_ROTATE TRUE
J 2
(-1500 3650);
DISPLAY 0.489362 (-1500 3650);
PAINT GREEN (-1500 3650);
DISPLAY INVISIBLE (-1500 3650);
FORCEPROP 2 LAST VOLTAGE 6.3V
J 2
(-1850 3700);
DISPLAY 0.553191 (-1850 3700);
DISPLAY INVISIBLE (-1850 3700);
FORCEPROP 1 LAST MATERIAL X6S
J 2
(-1491 3729);
DISPLAY 0.574468 (-1491 3729);
PAINT GREEN (-1491 3729);
DISPLAY INVISIBLE (-1491 3729);
FORCEPROP 2 LAST PACK_TYPE C0201
J 2
(-1675 3700);
DISPLAY 0.553191 (-1675 3700);
DISPLAY INVISIBLE (-1675 3700);
FORCEPROP 2 LAST TOLERANCE 20%
J 2
(-1575 3700);
DISPLAY 0.553191 (-1575 3700);
DISPLAY INVISIBLE (-1575 3700);
FORCEPROP 2 LAST CDS_LIB pure_quanta
J 2
(-1500 3650);
DISPLAY INVISIBLE (-1500 3650);
FORCEPROP 1 LAST CDS_LMAN_SYM_OUTLINE -25,50,25,-50
J 2
(-1500 3650);
DISPLAY 0.468085 (-1500 3650);
PAINT GREEN (-1500 3650);
DISPLAY INVISIBLE (-1500 3650);
FORCEPROP 1 LAST PART_NUMBER SP_CH4221MEE01
J 2
(-1616 3738);
DISPLAY 0.574468 (-1616 3738);
PAINT GREEN (-1616 3738);
DISPLAY INVISIBLE (-1616 3738);
FORCEPROP 1 LAST PATH I83
J 2
(-1500 3650);
DISPLAY 0.723404 (-1500 3650);
DISPLAY INVISIBLE (-1500 3650);
FORCEADD Q_CAP_DIFFBUS..2
R 2
(-1500 3700);
FORCEPROP 1 LAST LOCATION C1524
J 2
(-1250 3725);
DISPLAY 0.723404 (-1250 3725);
PAINT GREEN (-1250 3725);
FORCEPROP 2 LAST $SEC 1
J 2
(-1325 3775);
DISPLAY 0.680851 (-1325 3775);
PAINT MONO (-1325 3775);
DISPLAY INVISIBLE (-1325 3775);
FORCEPROP 2 LAST CDS_SEC 1
J 2
(-1325 3775);
DISPLAY 0.680851 (-1325 3775);
DISPLAY INVISIBLE (-1325 3775);
FORCEPROP 2 LASTPIN (-1425 3700) $PN 1
J 0
(-1415 3710);
DISPLAY 0.808511 (-1415 3710);
FORCEPROP 2 LASTPIN (-1575 3700) $PN 2
J 2
(-1585 3710);
DISPLAY 0.808511 (-1585 3710);
FORCEPROP 2 LAST VALUE DIFF BUS_0.22UF
J 2
(-1650 3700);
DISPLAY 0.553191 (-1650 3700);
FORCEPROP 1 LAST PIN_NAMES_ROTATE TRUE
J 2
(-1500 3700);
DISPLAY 0.489362 (-1500 3700);
PAINT GREEN (-1500 3700);
DISPLAY INVISIBLE (-1500 3700);
FORCEPROP 2 LAST VOLTAGE 6.3V
J 2
(-1850 3750);
DISPLAY 0.553191 (-1850 3750);
DISPLAY INVISIBLE (-1850 3750);
FORCEPROP 1 LAST MATERIAL X6S
J 2
(-1491 3779);
DISPLAY 0.574468 (-1491 3779);
PAINT GREEN (-1491 3779);
DISPLAY INVISIBLE (-1491 3779);
FORCEPROP 2 LAST PACK_TYPE C0201
J 2
(-1675 3750);
DISPLAY 0.553191 (-1675 3750);
DISPLAY INVISIBLE (-1675 3750);
FORCEPROP 2 LAST TOLERANCE 20%
J 2
(-1575 3750);
DISPLAY 0.553191 (-1575 3750);
DISPLAY INVISIBLE (-1575 3750);
FORCEPROP 2 LAST CDS_LIB pure_quanta
J 2
(-1500 3700);
DISPLAY INVISIBLE (-1500 3700);
FORCEPROP 1 LAST CDS_LMAN_SYM_OUTLINE -25,50,25,-50
J 2
(-1500 3700);
DISPLAY 0.468085 (-1500 3700);
PAINT GREEN (-1500 3700);
DISPLAY INVISIBLE (-1500 3700);
FORCEPROP 1 LAST PART_NUMBER SP_CH4221MEE01
J 2
(-1616 3788);
DISPLAY 0.574468 (-1616 3788);
PAINT GREEN (-1616 3788);
DISPLAY INVISIBLE (-1616 3788);
FORCEPROP 1 LAST PATH I84
J 2
(-1500 3700);
DISPLAY 0.723404 (-1500 3700);
DISPLAY INVISIBLE (-1500 3700);
FORCEADD Q_CAP_DIFFBUS..2
R 2
(-1500 3850);
FORCEPROP 1 LAST LOCATION C55
J 2
(-1250 3875);
DISPLAY 0.723404 (-1250 3875);
PAINT GREEN (-1250 3875);
FORCEPROP 2 LAST $SEC 1
J 2
(-1325 3925);
DISPLAY 0.680851 (-1325 3925);
PAINT MONO (-1325 3925);
DISPLAY INVISIBLE (-1325 3925);
FORCEPROP 2 LAST CDS_SEC 1
J 2
(-1325 3925);
DISPLAY 0.680851 (-1325 3925);
DISPLAY INVISIBLE (-1325 3925);
FORCEPROP 2 LASTPIN (-1425 3850) $PN 1
J 0
(-1415 3860);
DISPLAY 0.808511 (-1415 3860);
FORCEPROP 2 LASTPIN (-1575 3850) $PN 2
J 2
(-1585 3860);
DISPLAY 0.808511 (-1585 3860);
FORCEPROP 2 LAST VALUE DIFF BUS_0.22UF
J 2
(-1650 3850);
DISPLAY 0.553191 (-1650 3850);
FORCEPROP 1 LAST PIN_NAMES_ROTATE TRUE
J 2
(-1500 3850);
DISPLAY 0.489362 (-1500 3850);
PAINT GREEN (-1500 3850);
DISPLAY INVISIBLE (-1500 3850);
FORCEPROP 2 LAST VOLTAGE 6.3V
J 2
(-1850 3900);
DISPLAY 0.553191 (-1850 3900);
DISPLAY INVISIBLE (-1850 3900);
FORCEPROP 1 LAST MATERIAL X6S
J 2
(-1491 3929);
DISPLAY 0.574468 (-1491 3929);
PAINT GREEN (-1491 3929);
DISPLAY INVISIBLE (-1491 3929);
FORCEPROP 2 LAST PACK_TYPE C0201
J 2
(-1675 3900);
DISPLAY 0.553191 (-1675 3900);
DISPLAY INVISIBLE (-1675 3900);
FORCEPROP 2 LAST TOLERANCE 20%
J 2
(-1575 3900);
DISPLAY 0.553191 (-1575 3900);
DISPLAY INVISIBLE (-1575 3900);
FORCEPROP 1 LAST CDS_LMAN_SYM_OUTLINE -25,50,25,-50
J 2
(-1500 3850);
DISPLAY 0.468085 (-1500 3850);
PAINT GREEN (-1500 3850);
DISPLAY INVISIBLE (-1500 3850);
FORCEPROP 2 LAST CDS_LIB pure_quanta
J 2
(-1500 3850);
DISPLAY INVISIBLE (-1500 3850);
FORCEPROP 1 LAST PART_NUMBER SP_CH4221MEE01
J 2
(-1616 3938);
DISPLAY 0.574468 (-1616 3938);
PAINT GREEN (-1616 3938);
DISPLAY INVISIBLE (-1616 3938);
FORCEPROP 1 LAST PATH I85
J 2
(-1500 3850);
DISPLAY 0.723404 (-1500 3850);
DISPLAY INVISIBLE (-1500 3850);
FORCEADD Q_CAP_DIFFBUS..2
R 2
(-1500 3900);
FORCEPROP 1 LAST LOCATION C54
J 2
(-1250 3925);
DISPLAY 0.723404 (-1250 3925);
PAINT GREEN (-1250 3925);
FORCEPROP 2 LAST $SEC 1
J 2
(-1325 3975);
DISPLAY 0.680851 (-1325 3975);
PAINT MONO (-1325 3975);
DISPLAY INVISIBLE (-1325 3975);
FORCEPROP 2 LAST CDS_SEC 1
J 2
(-1325 3975);
DISPLAY 0.680851 (-1325 3975);
DISPLAY INVISIBLE (-1325 3975);
FORCEPROP 2 LASTPIN (-1425 3900) $PN 1
J 0
(-1415 3910);
DISPLAY 0.808511 (-1415 3910);
FORCEPROP 2 LASTPIN (-1575 3900) $PN 2
J 2
(-1585 3910);
DISPLAY 0.808511 (-1585 3910);
FORCEPROP 2 LAST VALUE DIFF BUS_0.22UF
J 2
(-1650 3900);
DISPLAY 0.553191 (-1650 3900);
FORCEPROP 1 LAST PIN_NAMES_ROTATE TRUE
J 2
(-1500 3900);
DISPLAY 0.489362 (-1500 3900);
PAINT GREEN (-1500 3900);
DISPLAY INVISIBLE (-1500 3900);
FORCEPROP 2 LAST VOLTAGE 6.3V
J 2
(-1850 3950);
DISPLAY 0.553191 (-1850 3950);
DISPLAY INVISIBLE (-1850 3950);
FORCEPROP 1 LAST MATERIAL X6S
J 2
(-1491 3979);
DISPLAY 0.574468 (-1491 3979);
PAINT GREEN (-1491 3979);
DISPLAY INVISIBLE (-1491 3979);
FORCEPROP 2 LAST PACK_TYPE C0201
J 2
(-1675 3950);
DISPLAY 0.553191 (-1675 3950);
DISPLAY INVISIBLE (-1675 3950);
FORCEPROP 2 LAST TOLERANCE 20%
J 2
(-1575 3950);
DISPLAY 0.553191 (-1575 3950);
DISPLAY INVISIBLE (-1575 3950);
FORCEPROP 1 LAST CDS_LMAN_SYM_OUTLINE -25,50,25,-50
J 2
(-1500 3900);
DISPLAY 0.468085 (-1500 3900);
PAINT GREEN (-1500 3900);
DISPLAY INVISIBLE (-1500 3900);
FORCEPROP 2 LAST CDS_LIB pure_quanta
J 2
(-1500 3900);
DISPLAY INVISIBLE (-1500 3900);
FORCEPROP 1 LAST PART_NUMBER SP_CH4221MEE01
J 2
(-1616 3988);
DISPLAY 0.574468 (-1616 3988);
PAINT GREEN (-1616 3988);
DISPLAY INVISIBLE (-1616 3988);
FORCEPROP 1 LAST PATH I86
J 2
(-1500 3900);
DISPLAY 0.723404 (-1500 3900);
DISPLAY INVISIBLE (-1500 3900);
FORCEADD TAP..1
(-975 2075);
FORCEPROP 3 LASTPIN (-1025 2075) SIG_NAME P5E_CPU1_P3_TX_C_DN<3>
J 0
(-1015 2085);
DISPLAY 0.659574 (-1015 2085);
PAINT MONO (-1015 2085);
DISPLAY INVISIBLE (-1015 2085);
FORCEPROP 1 LASTPIN (-1025 2075) BN 3
J 0
(-1037 2083);
DISPLAY 0.680851 (-1037 2083);
PAINT GREEN (-1037 2083);
FORCEPROP 2 LAST CDS_LIB standard
J 0
(-975 2075);
DISPLAY INVISIBLE (-975 2075);
FORCEPROP 1 LAST BODY_TYPE PLUMBING
J 0
(-975 2125);
DISPLAY 0.872340 (-975 2125);
PAINT GREEN (-975 2125);
DISPLAY INVISIBLE (-975 2125);
FORCEPROP 1 LAST HDL_TAP TRUE
J 0
(-650 1950);
DISPLAY 0.872340 (-650 1950);
DISPLAY INVISIBLE (-650 1950);
FORCEPROP 1 LAST PATH I87
J 0
(-977 2075);
DISPLAY 0.872340 (-977 2075);
PAINT GREEN (-977 2075);
DISPLAY INVISIBLE (-977 2075);
FORCEADD TAP..1
(-975 2475);
FORCEPROP 3 LASTPIN (-1025 2475) SIG_NAME P5E_CPU1_P3_TX_C_DN<5>
J 0
(-1015 2485);
DISPLAY 0.659574 (-1015 2485);
PAINT MONO (-1015 2485);
DISPLAY INVISIBLE (-1015 2485);
FORCEPROP 1 LASTPIN (-1025 2475) BN 5
J 0
(-1037 2483);
DISPLAY 0.680851 (-1037 2483);
PAINT GREEN (-1037 2483);
FORCEPROP 2 LAST CDS_LIB standard
J 0
(-975 2475);
DISPLAY INVISIBLE (-975 2475);
FORCEPROP 1 LAST BODY_TYPE PLUMBING
J 0
(-975 2525);
DISPLAY 0.872340 (-975 2525);
PAINT GREEN (-975 2525);
DISPLAY INVISIBLE (-975 2525);
FORCEPROP 1 LAST HDL_TAP TRUE
J 0
(-650 2350);
DISPLAY 0.872340 (-650 2350);
DISPLAY INVISIBLE (-650 2350);
FORCEPROP 1 LAST PATH I88
J 0
(-977 2475);
DISPLAY 0.872340 (-977 2475);
PAINT GREEN (-977 2475);
DISPLAY INVISIBLE (-977 2475);
FORCEADD TAP..1
(-975 2275);
FORCEPROP 3 LASTPIN (-1025 2275) SIG_NAME P5E_CPU1_P3_TX_C_DN<4>
J 0
(-1015 2285);
DISPLAY 0.659574 (-1015 2285);
PAINT MONO (-1015 2285);
DISPLAY INVISIBLE (-1015 2285);
FORCEPROP 1 LASTPIN (-1025 2275) BN 4
J 0
(-1037 2283);
DISPLAY 0.680851 (-1037 2283);
PAINT GREEN (-1037 2283);
FORCEPROP 2 LAST CDS_LIB standard
J 0
(-975 2275);
DISPLAY INVISIBLE (-975 2275);
FORCEPROP 1 LAST BODY_TYPE PLUMBING
J 0
(-975 2325);
DISPLAY 0.872340 (-975 2325);
PAINT GREEN (-975 2325);
DISPLAY INVISIBLE (-975 2325);
FORCEPROP 1 LAST HDL_TAP TRUE
J 0
(-650 2150);
DISPLAY 0.872340 (-650 2150);
DISPLAY INVISIBLE (-650 2150);
FORCEPROP 1 LAST PATH I89
J 0
(-977 2275);
DISPLAY 0.872340 (-977 2275);
PAINT GREEN (-977 2275);
DISPLAY INVISIBLE (-977 2275);
FORCEADD Q_CAP_DIFFBUS..2
R 2
(-1375 -350);
FORCEPROP 1 LAST LOCATION C1992
J 2
(-1150 -350);
DISPLAY 0.723404 (-1150 -350);
PAINT GREEN (-1150 -350);
FORCEPROP 0 LAST $SEC 1
J 0
(-1150 -300);
DISPLAY 0.680851 (-1150 -300);
PAINT MONO (-1150 -300);
DISPLAY INVISIBLE (-1150 -300);
FORCEPROP 0 LAST CDS_SEC 1
J 0
(-1150 -300);
DISPLAY 0.680851 (-1150 -300);
DISPLAY INVISIBLE (-1150 -300);
FORCEPROP 0 LASTPIN (-1300 -350) $PN 1
J 0
(-1290 -340);
DISPLAY 0.680851 (-1290 -340);
PAINT MONO (-1290 -340);
FORCEPROP 0 LASTPIN (-1450 -350) $PN 2
J 2
(-1460 -340);
DISPLAY 0.680851 (-1460 -340);
PAINT MONO (-1460 -340);
FORCEPROP 2 LAST VALUE DIFF BUS_0.22UF
J 2
(-1525 -350);
DISPLAY 0.553191 (-1525 -350);
FORCEPROP 2 LAST CDS_LIB pure_quanta
J 0
(-1375 -350);
DISPLAY INVISIBLE (-1375 -350);
FORCEPROP 1 LAST CDS_LMAN_SYM_OUTLINE -25,50,25,-50
J 2
(-1375 -350);
DISPLAY 0.468085 (-1375 -350);
PAINT GREEN (-1375 -350);
DISPLAY INVISIBLE (-1375 -350);
FORCEPROP 1 LAST PIN_NAMES_ROTATE TRUE
J 2
(-1375 -350);
DISPLAY 0.489362 (-1375 -350);
PAINT GREEN (-1375 -350);
DISPLAY INVISIBLE (-1375 -350);
FORCEPROP 2 LAST VOLTAGE 6.3V
J 2
(-1725 -300);
DISPLAY 0.553191 (-1725 -300);
DISPLAY INVISIBLE (-1725 -300);
FORCEPROP 1 LAST MATERIAL X6S
J 2
(-1366 -271);
DISPLAY 0.574468 (-1366 -271);
PAINT GREEN (-1366 -271);
DISPLAY INVISIBLE (-1366 -271);
FORCEPROP 2 LAST PACK_TYPE C0201
J 2
(-1550 -300);
DISPLAY 0.553191 (-1550 -300);
DISPLAY INVISIBLE (-1550 -300);
FORCEPROP 2 LAST TOLERANCE 20%
J 2
(-1450 -300);
DISPLAY 0.553191 (-1450 -300);
DISPLAY INVISIBLE (-1450 -300);
FORCEPROP 1 LAST PART_NUMBER SP_CH4221MEE01
J 2
(-1491 -262);
DISPLAY 0.574468 (-1491 -262);
PAINT GREEN (-1491 -262);
DISPLAY INVISIBLE (-1491 -262);
FORCEPROP 1 LAST PATH I9
J 2
(-1375 -350);
DISPLAY 0.723404 (-1375 -350);
DISPLAY INVISIBLE (-1375 -350);
FORCEADD TAP..1
(-775 2025);
FORCEPROP 3 LASTPIN (-825 2025) SIG_NAME P5E_CPU1_P3_TX_C_DP<3>
J 0
(-815 2035);
DISPLAY 0.659574 (-815 2035);
PAINT MONO (-815 2035);
DISPLAY INVISIBLE (-815 2035);
FORCEPROP 1 LASTPIN (-825 2025) BN 3
J 0
(-837 2033);
DISPLAY 0.680851 (-837 2033);
PAINT GREEN (-837 2033);
FORCEPROP 2 LAST CDS_LIB standard
J 0
(-775 2025);
DISPLAY INVISIBLE (-775 2025);
FORCEPROP 1 LAST BODY_TYPE PLUMBING
J 0
(-775 2075);
DISPLAY 0.872340 (-775 2075);
PAINT GREEN (-775 2075);
DISPLAY INVISIBLE (-775 2075);
FORCEPROP 1 LAST HDL_TAP TRUE
J 0
(-450 1900);
DISPLAY 0.872340 (-450 1900);
DISPLAY INVISIBLE (-450 1900);
FORCEPROP 1 LAST PATH I90
J 0
(-777 2025);
DISPLAY 0.872340 (-777 2025);
PAINT GREEN (-777 2025);
DISPLAY INVISIBLE (-777 2025);
FORCEADD TAP..1
(-775 2225);
FORCEPROP 3 LASTPIN (-825 2225) SIG_NAME P5E_CPU1_P3_TX_C_DP<4>
J 0
(-815 2235);
DISPLAY 0.659574 (-815 2235);
PAINT MONO (-815 2235);
DISPLAY INVISIBLE (-815 2235);
FORCEPROP 1 LASTPIN (-825 2225) BN 4
J 0
(-837 2233);
DISPLAY 0.680851 (-837 2233);
PAINT GREEN (-837 2233);
FORCEPROP 2 LAST CDS_LIB standard
J 0
(-775 2225);
DISPLAY INVISIBLE (-775 2225);
FORCEPROP 1 LAST BODY_TYPE PLUMBING
J 0
(-775 2275);
DISPLAY 0.872340 (-775 2275);
PAINT GREEN (-775 2275);
DISPLAY INVISIBLE (-775 2275);
FORCEPROP 1 LAST HDL_TAP TRUE
J 0
(-450 2100);
DISPLAY 0.872340 (-450 2100);
DISPLAY INVISIBLE (-450 2100);
FORCEPROP 1 LAST PATH I91
J 0
(-777 2225);
DISPLAY 0.872340 (-777 2225);
PAINT GREEN (-777 2225);
DISPLAY INVISIBLE (-777 2225);
FORCEADD TAP..1
(-775 2425);
FORCEPROP 3 LASTPIN (-825 2425) SIG_NAME P5E_CPU1_P3_TX_C_DP<5>
J 0
(-815 2435);
DISPLAY 0.659574 (-815 2435);
PAINT MONO (-815 2435);
DISPLAY INVISIBLE (-815 2435);
FORCEPROP 1 LASTPIN (-825 2425) BN 5
J 0
(-837 2433);
DISPLAY 0.680851 (-837 2433);
PAINT GREEN (-837 2433);
FORCEPROP 2 LAST CDS_LIB standard
J 0
(-775 2425);
DISPLAY INVISIBLE (-775 2425);
FORCEPROP 1 LAST BODY_TYPE PLUMBING
J 0
(-775 2475);
DISPLAY 0.872340 (-775 2475);
PAINT GREEN (-775 2475);
DISPLAY INVISIBLE (-775 2475);
FORCEPROP 1 LAST HDL_TAP TRUE
J 0
(-450 2300);
DISPLAY 0.872340 (-450 2300);
DISPLAY INVISIBLE (-450 2300);
FORCEPROP 1 LAST PATH I92
J 0
(-777 2425);
DISPLAY 0.872340 (-777 2425);
PAINT GREEN (-777 2425);
DISPLAY INVISIBLE (-777 2425);
FORCEADD TAP..1
(-975 2675);
FORCEPROP 3 LASTPIN (-1025 2675) SIG_NAME P5E_CPU1_P3_TX_C_DN<6>
J 0
(-1015 2685);
DISPLAY 0.659574 (-1015 2685);
PAINT MONO (-1015 2685);
DISPLAY INVISIBLE (-1015 2685);
FORCEPROP 1 LASTPIN (-1025 2675) BN 6
J 0
(-1037 2683);
DISPLAY 0.680851 (-1037 2683);
PAINT GREEN (-1037 2683);
FORCEPROP 2 LAST CDS_LIB standard
J 0
(-975 2675);
DISPLAY INVISIBLE (-975 2675);
FORCEPROP 1 LAST BODY_TYPE PLUMBING
J 0
(-975 2725);
DISPLAY 0.872340 (-975 2725);
PAINT GREEN (-975 2725);
DISPLAY INVISIBLE (-975 2725);
FORCEPROP 1 LAST HDL_TAP TRUE
J 0
(-650 2550);
DISPLAY 0.872340 (-650 2550);
DISPLAY INVISIBLE (-650 2550);
FORCEPROP 1 LAST PATH I93
J 0
(-977 2675);
DISPLAY 0.872340 (-977 2675);
PAINT GREEN (-977 2675);
DISPLAY INVISIBLE (-977 2675);
FORCEADD TAP..1
(-975 2875);
FORCEPROP 3 LASTPIN (-1025 2875) SIG_NAME P5E_CPU1_P3_TX_C_DN<7>
J 0
(-1015 2885);
DISPLAY 0.659574 (-1015 2885);
PAINT MONO (-1015 2885);
DISPLAY INVISIBLE (-1015 2885);
FORCEPROP 1 LASTPIN (-1025 2875) BN 7
J 0
(-1037 2883);
DISPLAY 0.680851 (-1037 2883);
PAINT GREEN (-1037 2883);
FORCEPROP 2 LAST CDS_LIB standard
J 0
(-975 2875);
DISPLAY INVISIBLE (-975 2875);
FORCEPROP 1 LAST BODY_TYPE PLUMBING
J 0
(-975 2925);
DISPLAY 0.872340 (-975 2925);
PAINT GREEN (-975 2925);
DISPLAY INVISIBLE (-975 2925);
FORCEPROP 1 LAST HDL_TAP TRUE
J 0
(-650 2750);
DISPLAY 0.872340 (-650 2750);
DISPLAY INVISIBLE (-650 2750);
FORCEPROP 1 LAST PATH I94
J 0
(-977 2875);
DISPLAY 0.872340 (-977 2875);
PAINT GREEN (-977 2875);
DISPLAY INVISIBLE (-977 2875);
FORCEADD TAP..1
(-775 2625);
FORCEPROP 3 LASTPIN (-825 2625) SIG_NAME P5E_CPU1_P3_TX_C_DP<6>
J 0
(-815 2635);
DISPLAY 0.659574 (-815 2635);
PAINT MONO (-815 2635);
DISPLAY INVISIBLE (-815 2635);
FORCEPROP 1 LASTPIN (-825 2625) BN 6
J 0
(-837 2633);
DISPLAY 0.680851 (-837 2633);
PAINT GREEN (-837 2633);
FORCEPROP 2 LAST CDS_LIB standard
J 0
(-775 2625);
DISPLAY INVISIBLE (-775 2625);
FORCEPROP 1 LAST BODY_TYPE PLUMBING
J 0
(-775 2675);
DISPLAY 0.872340 (-775 2675);
PAINT GREEN (-775 2675);
DISPLAY INVISIBLE (-775 2675);
FORCEPROP 1 LAST HDL_TAP TRUE
J 0
(-450 2500);
DISPLAY 0.872340 (-450 2500);
DISPLAY INVISIBLE (-450 2500);
FORCEPROP 1 LAST PATH I95
J 0
(-777 2625);
DISPLAY 0.872340 (-777 2625);
PAINT GREEN (-777 2625);
DISPLAY INVISIBLE (-777 2625);
FORCEADD TAP..1
(-775 2825);
FORCEPROP 3 LASTPIN (-825 2825) SIG_NAME P5E_CPU1_P3_TX_C_DP<7>
J 0
(-815 2835);
DISPLAY 0.659574 (-815 2835);
PAINT MONO (-815 2835);
DISPLAY INVISIBLE (-815 2835);
FORCEPROP 1 LASTPIN (-825 2825) BN 7
J 0
(-837 2833);
DISPLAY 0.680851 (-837 2833);
PAINT GREEN (-837 2833);
FORCEPROP 2 LAST CDS_LIB standard
J 0
(-775 2825);
DISPLAY INVISIBLE (-775 2825);
FORCEPROP 1 LAST BODY_TYPE PLUMBING
J 0
(-775 2875);
DISPLAY 0.872340 (-775 2875);
PAINT GREEN (-775 2875);
DISPLAY INVISIBLE (-775 2875);
FORCEPROP 1 LAST HDL_TAP TRUE
J 0
(-450 2700);
DISPLAY 0.872340 (-450 2700);
DISPLAY INVISIBLE (-450 2700);
FORCEPROP 1 LAST PATH I96
J 0
(-777 2825);
DISPLAY 0.872340 (-777 2825);
PAINT GREEN (-777 2825);
DISPLAY INVISIBLE (-777 2825);
FORCEADD TAP..1
(-950 3100);
FORCEPROP 3 LASTPIN (-1000 3100) SIG_NAME P5E_CPU1_P3_TX_C_DN<8>
J 0
(-990 3110);
DISPLAY 0.659574 (-990 3110);
PAINT MONO (-990 3110);
DISPLAY INVISIBLE (-990 3110);
FORCEPROP 1 LASTPIN (-1000 3100) BN 8
J 0
(-1012 3108);
DISPLAY 0.680851 (-1012 3108);
PAINT GREEN (-1012 3108);
FORCEPROP 2 LAST CDS_LIB standard
J 0
(-950 3100);
DISPLAY INVISIBLE (-950 3100);
FORCEPROP 1 LAST BODY_TYPE PLUMBING
J 0
(-950 3150);
DISPLAY 0.872340 (-950 3150);
PAINT GREEN (-950 3150);
DISPLAY INVISIBLE (-950 3150);
FORCEPROP 1 LAST HDL_TAP TRUE
J 0
(-625 2975);
DISPLAY 0.872340 (-625 2975);
DISPLAY INVISIBLE (-625 2975);
FORCEPROP 1 LAST PATH I97
J 0
(-952 3100);
DISPLAY 0.872340 (-952 3100);
PAINT GREEN (-952 3100);
DISPLAY INVISIBLE (-952 3100);
FORCEADD TAP..1
(-950 3500);
FORCEPROP 3 LASTPIN (-1000 3500) SIG_NAME P5E_CPU1_P3_TX_C_DN<10>
J 0
(-990 3510);
DISPLAY 0.659574 (-990 3510);
PAINT MONO (-990 3510);
DISPLAY INVISIBLE (-990 3510);
FORCEPROP 1 LASTPIN (-1000 3500) BN 10
J 0
(-1012 3508);
DISPLAY 0.680851 (-1012 3508);
PAINT GREEN (-1012 3508);
FORCEPROP 2 LAST CDS_LIB standard
J 0
(-950 3500);
DISPLAY INVISIBLE (-950 3500);
FORCEPROP 1 LAST BODY_TYPE PLUMBING
J 0
(-950 3550);
DISPLAY 0.872340 (-950 3550);
PAINT GREEN (-950 3550);
DISPLAY INVISIBLE (-950 3550);
FORCEPROP 1 LAST HDL_TAP TRUE
J 0
(-625 3375);
DISPLAY 0.872340 (-625 3375);
DISPLAY INVISIBLE (-625 3375);
FORCEPROP 1 LAST PATH I98
J 0
(-952 3500);
DISPLAY 0.872340 (-952 3500);
PAINT GREEN (-952 3500);
DISPLAY INVISIBLE (-952 3500);
FORCEADD TAP..1
(-950 3300);
FORCEPROP 3 LASTPIN (-1000 3300) SIG_NAME P5E_CPU1_P3_TX_C_DN<9>
J 0
(-990 3310);
DISPLAY 0.659574 (-990 3310);
PAINT MONO (-990 3310);
DISPLAY INVISIBLE (-990 3310);
FORCEPROP 1 LASTPIN (-1000 3300) BN 9
J 0
(-1012 3308);
DISPLAY 0.680851 (-1012 3308);
PAINT GREEN (-1012 3308);
FORCEPROP 2 LAST CDS_LIB standard
J 0
(-950 3300);
DISPLAY INVISIBLE (-950 3300);
FORCEPROP 1 LAST BODY_TYPE PLUMBING
J 0
(-950 3350);
DISPLAY 0.872340 (-950 3350);
PAINT GREEN (-950 3350);
DISPLAY INVISIBLE (-950 3350);
FORCEPROP 1 LAST HDL_TAP TRUE
J 0
(-625 3175);
DISPLAY 0.872340 (-625 3175);
DISPLAY INVISIBLE (-625 3175);
FORCEPROP 1 LAST PATH I99
J 0
(-952 3300);
DISPLAY 0.872340 (-952 3300);
PAINT GREEN (-952 3300);
DISPLAY INVISIBLE (-952 3300);
FORCEADD QUANTA_TITLE_BLOCK_C..1
(5400 -1725);
FORCEPROP 0 LAST CDS_CON_LAST_MODIFIED Thu Sep 14 16:12:36 2023
J 0
(3515 -1710);
DISPLAY INVISIBLE (3515 -1710);
FORCEPROP 1 LAST CUSTOM_TXT_CDS <CON_LAST_MODIFIED>
J 0
(3515 -1710);
DISPLAY 0.978723 (3515 -1710);
FORCEPROP 2 LAST CUSTOM_TXT_CDS <XR_PAGE_TITLE>
J 0
(-2490 3525);
DISPLAY 0.638298 (-2490 3525);
PAINT PINK (-2490 3525);
DISPLAY INVISIBLE (-2490 3525);
FORCEPROP 2 LAST CUSTOM_TXT_CDS <Q_NUMBER>
J 0
(3997 -1622);
DISPLAY 1.212766 (3997 -1622);
FORCEPROP 1 LAST CUSTOM_TXT_CDS <NAME_2>
J 0
(2225 -1675);
FORCEPROP 1 LAST CUSTOM_TXT_CDS <NAME_1>
J 0
(2225 -1550);
FORCEPROP 1 LAST CUSTOM_TXT_CDS <Q_PROJ>
J 0
(3018 -1623);
DISPLAY 1.212766 (3018 -1623);
FORCEPROP 1 LAST CUSTOM_TXT_CDS <Q_REV>
J 0
(5216 -1622);
DISPLAY 1.212766 (5216 -1622);
FORCEPROP 1 LAST CUSTOM_TXT_CDS <CON_PAGE_NUM> OF <CON_TOTAL_PAGES>
J 0
(4954 -1707);
DISPLAY 0.978723 (4954 -1707);
FORCEPROP 1 LAST Q_TITLE PCIE AC-COUPLE CAPS 5/5
J 0
(-3966 -1699);
DISPLAY 2.446809 (-3966 -1699);
PAINT GREEN (-3966 -1699);
FORCEPROP 2 LAST CDS_LIB pure_quanta
J 0
(5400 -1725);
DISPLAY INVISIBLE (5400 -1725);
FORCEPROP 1 LAST CDS_LMAN_SYM_OUTLINE -9475,6775,100,-125
J 0
(5400 -1725);
DISPLAY 0.468085 (5400 -1725);
PAINT GREEN (5400 -1725);
DISPLAY INVISIBLE (5400 -1725);
FORCEPROP 2 LAST PAGE_BORDER TRUE
J 0
(-2490 3525);
DISPLAY 0.638298 (-2490 3525);
PAINT PINK (-2490 3525);
DISPLAY INVISIBLE (-2490 3525);
FORCEPROP 2 LAST CDS_XR_PAGE_TITLE CR-67 : @T6G_MB_LIB.T6G(SCH_1):PAGE67
J 0
(-2490 3525);
DISPLAY 0.638298 (-2490 3525);
PAINT PINK (-2490 3525);
DISPLAY INVISIBLE (-2490 3525);
FORCEPROP 1 LAST COMMENT_BODY TRUE
J 0
(5412 -1738);
DISPLAY 0.978723 (5412 -1738);
PAINT GREEN (5412 -1738);
DISPLAY INVISIBLE (5412 -1738);
FORCEPROP 1 LAST Q_DEPT CCBU
J 1
(1637 -1676);
DISPLAY 1.957447 (1637 -1676);
PAINT GREEN (1637 -1676);
DISPLAY INVISIBLE (1637 -1676);
WIRE 17 -1 (2100 2475)(2100 2675);
WIRE 17 -1 (2100 2275)(2100 2475);
WIRE 17 -1 (2100 2675)(2100 2875);
WIRE 17 -1 (1250 2875)(2100 2875);
FORCEPROP 2 LAST SIG_NAME P5E_CPU1_G1_TX_DP<7:0>
J 0
(1290 2885);
DISPLAY 0.680851 (1290 2885);
PAINT WHITE (1290 2885);
WIRE 17 -1 (3925 3275)(3925 3075);
WIRE 17 -1 (3925 3475)(3925 3275);
WIRE 17 -1 (3925 3675)(3925 3475);
WIRE 17 -1 (3925 3675)(3925 3875);
WIRE 17 -1 (3925 4075)(3925 3875);
WIRE 17 -1 (3925 4275)(3925 4075);
WIRE 17 -1 (3925 4475)(3925 4275);
WIRE 17 -1 (3925 4475)(4825 4475);
FORCEPROP 2 LAST SIG_NAME P5E_CPU1_G1_TX_C_DP<15:8>
J 0
(3965 4485);
DISPLAY 0.680851 (3965 4485);
PAINT WHITE (3965 4485);
WIRE 17 -1 (3725 3525)(3725 3325);
WIRE 17 -1 (3725 3725)(3725 3525);
WIRE 17 -1 (3725 3325)(3725 3125);
WIRE 17 -1 (3725 3725)(3725 3925);
WIRE 17 -1 (3725 4125)(3725 3925);
WIRE 17 -1 (3725 4325)(3725 4125);
WIRE 17 -1 (3725 4525)(3725 4325);
WIRE 17 -1 (3725 4525)(4825 4525);
FORCEPROP 2 LAST SIG_NAME P5E_CPU1_G1_TX_C_DN<15:8>
J 0
(3965 4535);
DISPLAY 0.680851 (3965 4535);
PAINT WHITE (3965 4535);
WIRE 17 -1 (3925 2875)(4825 2875);
FORCEPROP 2 LAST SIG_NAME P5E_CPU1_G1_TX_C_DP<7:0>
J 0
(3965 2885);
DISPLAY 0.680851 (3965 2885);
PAINT WHITE (3965 2885);
WIRE 17 -1 (2350 4525)(2350 4325);
WIRE 17 -1 (1250 4525)(2350 4525);
FORCEPROP 2 LAST SIG_NAME P5E_CPU1_G1_TX_DN<15:8>
J 0
(1290 4535);
DISPLAY 0.680851 (1290 4535);
PAINT WHITE (1290 4535);
WIRE 17 -1 (2350 4325)(2350 4125);
WIRE 17 -1 (2350 4125)(2350 3925);
WIRE 17 -1 (2350 3725)(2350 3925);
WIRE 17 -1 (2100 4275)(2100 4475);
WIRE 17 -1 (2100 4075)(2100 4275);
WIRE 17 -1 (1250 4475)(2100 4475);
FORCEPROP 2 LAST SIG_NAME P5E_CPU1_G1_TX_DP<15:8>
J 0
(1290 4485);
DISPLAY 0.680851 (1290 4485);
PAINT WHITE (1290 4485);
WIRE 17 -1 (2100 3875)(2100 4075);
WIRE 17 -1 (3725 2925)(4825 2925);
FORCEPROP 2 LAST SIG_NAME P5E_CPU1_G1_TX_C_DN<7:0>
J 0
(3965 2935);
DISPLAY 0.680851 (3965 2935);
PAINT WHITE (3965 2935);
WIRE 17 -1 (3925 2875)(3925 2675);
WIRE 17 -1 (3725 2925)(3725 2725);
WIRE 17 -1 (3725 2725)(3725 2525);
WIRE 17 -1 (3725 2525)(3725 2325);
WIRE 17 -1 (3725 2125)(3725 2325);
WIRE 17 -1 (3925 2675)(3925 2475);
WIRE 17 -1 (3925 2475)(3925 2275);
WIRE 17 -1 (3925 2075)(3925 2275);
WIRE 17 -1 (3725 2125)(3725 1925);
WIRE 17 -1 (3925 2075)(3925 1875);
WIRE 17 -1 (3725 1925)(3725 1725);
WIRE 17 -1 (3725 1725)(3725 1525);
WIRE 17 -1 (3925 1875)(3925 1675);
WIRE 17 -1 (3925 1675)(3925 1475);
WIRE 17 -1 (2350 3725)(2350 3525);
WIRE 17 -1 (2350 3525)(2350 3325);
WIRE 17 -1 (2350 3325)(2350 3125);
WIRE 17 -1 (2100 3675)(2100 3875);
WIRE 17 -1 (2100 3475)(2100 3675);
WIRE 17 -1 (2100 3275)(2100 3475);
WIRE 17 -1 (2100 3075)(2100 3275);
WIRE 17 -1 (2350 2925)(2350 2725);
WIRE 17 -1 (1250 2925)(2350 2925);
FORCEPROP 2 LAST SIG_NAME P5E_CPU1_G1_TX_DN<7:0>
J 0
(1290 2935);
DISPLAY 0.680851 (1290 2935);
PAINT WHITE (1290 2935);
WIRE 17 -1 (2350 2725)(2350 2525);
WIRE 17 -1 (2350 2525)(2350 2325);
WIRE 17 -1 (2350 2125)(2350 2325);
WIRE 17 -1 (2350 2125)(2350 1925);
WIRE 17 -1 (2350 1925)(2350 1725);
WIRE 17 -1 (2350 1725)(2350 1525);
WIRE 17 -1 (2100 2075)(2100 2275);
WIRE 17 -1 (2100 1875)(2100 2075);
WIRE 17 -1 (2100 1675)(2100 1875);
WIRE 17 -1 (2100 1475)(2100 1675);
WIRE 17 -1 (3750 50)(4850 50);
FORCEPROP 2 LAST SIG_NAME P3E_CPU1_P4_TX_C_DP<3:0>
J 0
(4065 60);
DISPLAY 0.680851 (4065 60);
WIRE 17 -1 (3950 0)(3950 -200);
WIRE 17 -1 (3950 0)(4850 0);
FORCEPROP 2 LAST SIG_NAME P3E_CPU1_P4_TX_C_DN<3:0>
J 0
(4040 10);
DISPLAY 0.680851 (4040 10);
WIRE 17 -1 (1275 50)(2375 50);
FORCEPROP 2 LAST SIG_NAME P3E_CPU1_P4_TX_DP<3:0>
J 0
(1390 60);
DISPLAY 0.680851 (1390 60);
WIRE 17 -1 (2125 -200)(2125 0);
WIRE 17 -1 (2125 -400)(2125 -200);
WIRE 17 -1 (1275 0)(2125 0);
FORCEPROP 2 LAST SIG_NAME P3E_CPU1_P4_TX_DN<3:0>
J 0
(1365 10);
DISPLAY 0.680851 (1365 10);
WIRE 17 -1 (3750 -350)(3750 -550);
WIRE 17 -1 (3750 -150)(3750 -350);
WIRE 17 -1 (3750 50)(3750 -150);
WIRE 17 -1 (3950 -400)(3950 -600);
WIRE 17 -1 (3950 -200)(3950 -400);
WIRE 17 -1 (2125 -600)(2125 -400);
WIRE 17 -1 (2375 -350)(2375 -550);
WIRE 17 -1 (2375 -150)(2375 -350);
WIRE 17 -1 (2375 50)(2375 -150);
WIRE 17 -1 (-700 4275)(-700 4075);
WIRE 17 -1 (-700 4475)(-700 4275);
WIRE 17 -1 (-700 4075)(-700 3875);
WIRE 17 -1 (-700 3675)(-700 3875);
WIRE 17 -1 (-700 4475)(200 4475);
FORCEPROP 2 LAST SIG_NAME P5E_CPU1_P3_TX_C_DP<15:8>
J 0
(-660 4485);
DISPLAY 0.680851 (-660 4485);
PAINT WHITE (-660 4485);
WIRE 17 -1 (-900 4325)(-900 4125);
WIRE 17 -1 (-900 4525)(-900 4325);
WIRE 17 -1 (-900 4125)(-900 3925);
WIRE 17 -1 (-900 3725)(-900 3925);
WIRE 17 -1 (-900 4525)(200 4525);
FORCEPROP 2 LAST SIG_NAME P5E_CPU1_P3_TX_C_DN<15:8>
J 0
(-660 4535);
DISPLAY 0.680851 (-660 4535);
PAINT WHITE (-660 4535);
WIRE 17 -1 (-2525 3875)(-2525 4075);
WIRE 17 -1 (-2525 3675)(-2525 3875);
WIRE 17 -1 (-2525 4075)(-2525 4275);
WIRE 17 -1 (-2525 4275)(-2525 4475);
WIRE 17 -1 (-2525 3475)(-2525 3675);
WIRE 17 -1 (-2525 3275)(-2525 3475);
WIRE 17 -1 (-3375 4475)(-2525 4475);
FORCEPROP 2 LAST SIG_NAME P5E_CPU1_P3_TX_DP<15:8>
J 0
(-3335 4485);
DISPLAY 0.680851 (-3335 4485);
PAINT WHITE (-3335 4485);
WIRE 17 -1 (-2275 4325)(-2275 4125);
WIRE 17 -1 (-2275 4525)(-2275 4325);
WIRE 17 -1 (-2275 4125)(-2275 3925);
WIRE 17 -1 (-2275 3725)(-2275 3925);
WIRE 17 -1 (-3375 4525)(-2275 4525);
FORCEPROP 2 LAST SIG_NAME P5E_CPU1_P3_TX_DN<15:8>
J 0
(-3335 4535);
DISPLAY 0.680851 (-3335 4535);
PAINT WHITE (-3335 4535);
WIRE 17 -1 (-725 2850)(-725 2650);
WIRE 17 -1 (-725 2850)(175 2850);
FORCEPROP 2 LAST SIG_NAME P5E_CPU1_P3_TX_C_DP<7:0>
J 0
(-685 2860);
DISPLAY 0.680851 (-685 2860);
PAINT WHITE (-685 2860);
WIRE 17 -1 (-925 2900)(-925 2700);
WIRE 17 -1 (-925 2900)(175 2900);
FORCEPROP 2 LAST SIG_NAME P5E_CPU1_P3_TX_C_DN<7:0>
J 0
(-685 2910);
DISPLAY 0.680851 (-685 2910);
PAINT WHITE (-685 2910);
WIRE 17 -1 (-925 2500)(-925 2300);
WIRE 17 -1 (-925 2700)(-925 2500);
WIRE 17 -1 (-925 2100)(-925 2300);
WIRE 17 -1 (-925 2100)(-925 1900);
WIRE 17 -1 (-925 1900)(-925 1700);
WIRE 17 -1 (-925 1700)(-925 1500);
WIRE 17 -1 (-725 2650)(-725 2450);
WIRE 17 -1 (-725 2450)(-725 2250);
WIRE 17 -1 (-725 2050)(-725 2250);
WIRE 17 -1 (-725 2050)(-725 1850);
WIRE 17 -1 (-725 1850)(-725 1650);
WIRE 17 -1 (-725 1650)(-725 1450);
WIRE 17 -1 (-700 3275)(-700 3075);
WIRE 17 -1 (-700 3475)(-700 3275);
WIRE 17 -1 (-700 3675)(-700 3475);
WIRE 17 -1 (-900 3325)(-900 3125);
WIRE 17 -1 (-900 3525)(-900 3325);
WIRE 17 -1 (-900 3725)(-900 3525);
WIRE 17 -1 (-775 125)(325 125);
FORCEPROP 2 LAST SIG_NAME P3E_CPU0_P4_TX_C_DP<3:0>
J 0
(-485 135);
DISPLAY 0.680851 (-485 135);
WIRE 17 -1 (-575 75)(325 75);
FORCEPROP 2 LAST SIG_NAME P3E_CPU0_P4_TX_C_DN<3:0>
J 0
(-485 85);
DISPLAY 0.680851 (-485 85);
WIRE 17 -1 (-3250 125)(-2150 125);
FORCEPROP 2 LAST SIG_NAME P3E_CPU0_P4_TX_DP<3:0>
J 0
(-3160 135);
DISPLAY 0.680851 (-3160 135);
WIRE 17 -1 (-2300 2900)(-2300 2700);
WIRE 17 -1 (-3400 2900)(-2300 2900);
FORCEPROP 2 LAST SIG_NAME P5E_CPU1_P3_TX_DN<7:0>
J 0
(-3360 2910);
DISPLAY 0.680851 (-3360 2910);
PAINT WHITE (-3360 2910);
WIRE 17 -1 (-2300 2700)(-2300 2500);
WIRE 17 -1 (-2300 2500)(-2300 2300);
WIRE 17 -1 (-2300 2100)(-2300 2300);
WIRE 17 -1 (-2550 2650)(-2550 2850);
WIRE 17 -1 (-2550 2450)(-2550 2650);
WIRE 17 -1 (-3400 2850)(-2550 2850);
FORCEPROP 2 LAST SIG_NAME P5E_CPU1_P3_TX_DP<7:0>
J 0
(-3360 2860);
DISPLAY 0.680851 (-3360 2860);
PAINT WHITE (-3360 2860);
WIRE 17 -1 (-2550 2250)(-2550 2450);
WIRE 17 -1 (-2300 2100)(-2300 1900);
WIRE 17 -1 (-2300 1900)(-2300 1700);
WIRE 17 -1 (-2300 1700)(-2300 1500);
WIRE 17 -1 (-2550 2050)(-2550 2250);
WIRE 17 -1 (-2550 1850)(-2550 2050);
WIRE 17 -1 (-2550 1650)(-2550 1850);
WIRE 17 -1 (-2550 1450)(-2550 1650);
WIRE 17 -1 (-2525 3075)(-2525 3275);
WIRE 17 -1 (-2275 3325)(-2275 3125);
WIRE 17 -1 (-2275 3525)(-2275 3325);
WIRE 17 -1 (-2275 3725)(-2275 3525);
WIRE 17 -1 (-2400 -125)(-2400 75);
WIRE 17 -1 (-2400 -325)(-2400 -125);
WIRE 17 -1 (-3250 75)(-2400 75);
FORCEPROP 2 LAST SIG_NAME P3E_CPU0_P4_TX_DN<3:0>
J 0
(-3160 85);
DISPLAY 0.680851 (-3160 85);
WIRE 17 -1 (-775 125)(-775 -75);
WIRE 17 -1 (-575 75)(-575 -125);
WIRE 17 -1 (-775 -75)(-775 -275);
WIRE 17 -1 (-775 -275)(-775 -475);
WIRE 17 -1 (-575 -125)(-575 -325);
WIRE 17 -1 (-575 -325)(-575 -525);
WIRE 17 -1 (-2150 -275)(-2150 -475);
WIRE 17 -1 (-2150 -75)(-2150 -275);
WIRE 17 -1 (-2150 125)(-2150 -75);
WIRE 17 -1 (-2400 -525)(-2400 -325);
WIRE 16 -1 (-1450 -550)(-2300 -550);
WIRE 16 -1 (-1450 -350)(-2300 -350);
WIRE 16 -1 (-1450 -150)(-2300 -150);
WIRE 16 -1 (-1450 -300)(-2050 -300);
WIRE 16 -1 (-1450 -100)(-2050 -100);
WIRE 16 -1 (-1450 -500)(-2050 -500);
WIRE 16 -1 (-1300 -550)(-675 -550);
WIRE 16 -1 (-1300 -500)(-875 -500);
WIRE 16 -1 (-1300 -350)(-675 -350);
WIRE 16 -1 (-1300 -300)(-875 -300);
WIRE 16 -1 (-1300 -150)(-675 -150);
WIRE 16 -1 (-1300 -100)(-875 -100);
WIRE 16 -1 (-1450 50)(-2300 50);
WIRE 16 -1 (-1600 2275)(-2200 2275);
WIRE 16 -1 (-1575 3900)(-2175 3900);
WIRE 16 -1 (-1575 3700)(-2175 3700);
WIRE 16 -1 (-1575 3850)(-2425 3850);
WIRE 16 -1 (-1575 3650)(-2425 3650);
WIRE 16 -1 (-1575 3300)(-2175 3300);
WIRE 16 -1 (-1575 3500)(-2175 3500);
WIRE 16 -1 (-1575 3100)(-2175 3100);
WIRE 16 -1 (-1575 3450)(-2425 3450);
WIRE 16 -1 (-1575 3050)(-2425 3050);
WIRE 16 -1 (-1575 3250)(-2425 3250);
WIRE 16 -1 (-1600 2825)(-2450 2825);
WIRE 16 -1 (-1600 1425)(-2450 1425);
WIRE 16 -1 (-1600 1625)(-2450 1625);
WIRE 16 -1 (-1600 1475)(-2200 1475);
WIRE 16 -1 (-1600 1675)(-2200 1675);
WIRE 16 -1 (-1600 1825)(-2450 1825);
WIRE 16 -1 (-1600 2025)(-2450 2025);
WIRE 16 -1 (-1600 2225)(-2450 2225);
WIRE 16 -1 (-1600 1875)(-2200 1875);
WIRE 16 -1 (-1600 2075)(-2200 2075);
WIRE 16 -1 (-1600 2425)(-2450 2425);
WIRE 16 -1 (-1600 2625)(-2450 2625);
WIRE 16 -1 (-1600 2475)(-2200 2475);
WIRE 16 -1 (-1600 2675)(-2200 2675);
WIRE 16 -1 (-1600 2875)(-2200 2875);
WIRE 16 -1 (-1450 100)(-2050 100);
WIRE 16 -1 (-1300 50)(-675 50);
WIRE 16 -1 (-1300 100)(-875 100);
WIRE 16 -1 (-1450 1425)(-825 1425);
WIRE 16 -1 (-1450 1475)(-1025 1475);
WIRE 16 -1 (-1450 1625)(-825 1625);
WIRE 16 -1 (-1450 1825)(-825 1825);
WIRE 16 -1 (-1450 1675)(-1025 1675);
WIRE 16 -1 (-1450 1875)(-1025 1875);
WIRE 16 -1 (-1425 3850)(-800 3850);
WIRE 16 -1 (-1425 3900)(-1000 3900);
WIRE 16 -1 (-1425 3650)(-800 3650);
WIRE 16 -1 (-1425 3700)(-1000 3700);
WIRE 16 -1 (-1425 3300)(-1000 3300);
WIRE 16 -1 (-1425 3450)(-800 3450);
WIRE 16 -1 (-1425 3500)(-1000 3500);
WIRE 16 -1 (-1425 3100)(-1000 3100);
WIRE 16 -1 (-1425 3250)(-800 3250);
WIRE 16 -1 (-1425 3050)(-800 3050);
WIRE 16 -1 (-1450 2875)(-1025 2875);
WIRE 16 -1 (-1450 2825)(-825 2825);
WIRE 16 -1 (-1450 2025)(-825 2025);
WIRE 16 -1 (-1450 2225)(-825 2225);
WIRE 16 -1 (-1450 2425)(-825 2425);
WIRE 16 -1 (-1450 2475)(-1025 2475);
WIRE 16 -1 (-1450 2075)(-1025 2075);
WIRE 16 -1 (-1450 2275)(-1025 2275);
WIRE 16 -1 (-1450 2675)(-1025 2675);
WIRE 16 -1 (-1450 2625)(-825 2625);
WIRE 16 -1 (-1575 4300)(-2175 4300);
WIRE 16 -1 (-1575 4500)(-2175 4500);
WIRE 16 -1 (-1575 4100)(-2175 4100);
WIRE 16 -1 (-1575 4450)(-2425 4450);
WIRE 16 -1 (-1575 4250)(-2425 4250);
WIRE 16 -1 (-1575 4050)(-2425 4050);
WIRE 16 -1 (-1425 4300)(-1000 4300);
WIRE 16 -1 (-1425 4450)(-800 4450);
WIRE 16 -1 (-1425 4500)(-1000 4500);
WIRE 16 -1 (-1425 4100)(-1000 4100);
WIRE 16 -1 (-1425 4250)(-800 4250);
WIRE 16 -1 (-1425 4050)(-800 4050);
WIRE 16 -1 (3075 -175)(2475 -175);
WIRE 16 -1 (3075 -225)(2225 -225);
WIRE 16 -1 (3075 -425)(2225 -425);
WIRE 16 -1 (3075 -375)(2475 -375);
WIRE 16 -1 (3075 -575)(2475 -575);
WIRE 16 -1 (3075 -625)(2225 -625);
WIRE 16 -1 (3225 -225)(3850 -225);
WIRE 16 -1 (3225 -375)(3650 -375);
WIRE 16 -1 (3225 -425)(3850 -425);
WIRE 16 -1 (3225 -175)(3650 -175);
WIRE 16 -1 (3225 -625)(3850 -625);
WIRE 16 -1 (3225 -575)(3650 -575);
WIRE 16 -1 (3075 -25)(2225 -25);
WIRE 16 -1 (3075 25)(2475 25);
WIRE 16 -1 (3050 1650)(2200 1650);
WIRE 16 -1 (3050 1500)(2450 1500);
WIRE 16 -1 (3050 1700)(2450 1700);
WIRE 16 -1 (3050 1850)(2200 1850);
WIRE 16 -1 (3050 1900)(2450 1900);
WIRE 16 -1 (3050 1450)(2200 1450);
WIRE 16 -1 (3225 -25)(3850 -25);
WIRE 16 -1 (3225 25)(3650 25);
WIRE 16 -1 (3200 1500)(3625 1500);
WIRE 16 -1 (3200 1650)(3825 1650);
WIRE 16 -1 (3200 1700)(3625 1700);
WIRE 16 -1 (3200 1850)(3825 1850);
WIRE 16 -1 (3200 1900)(3625 1900);
WIRE 16 -1 (3200 1450)(3825 1450);
WIRE 16 -1 (3050 3450)(2200 3450);
WIRE 16 -1 (3050 2700)(2450 2700);
WIRE 16 -1 (3050 2050)(2200 2050);
WIRE 16 -1 (3050 2250)(2200 2250);
WIRE 16 -1 (3050 2300)(2450 2300);
WIRE 16 -1 (3050 2100)(2450 2100);
WIRE 16 -1 (3050 2450)(2200 2450);
WIRE 16 -1 (3050 2850)(2200 2850);
WIRE 16 -1 (3050 2500)(2450 2500);
WIRE 16 -1 (3050 2900)(2450 2900);
WIRE 16 -1 (3050 3250)(2200 3250);
WIRE 16 -1 (3050 3050)(2200 3050);
WIRE 16 -1 (3050 3100)(2450 3100);
WIRE 16 -1 (3050 3300)(2450 3300);
WIRE 16 -1 (3050 3500)(2450 3500);
WIRE 16 -1 (3050 3650)(2200 3650);
WIRE 16 -1 (3050 3850)(2200 3850);
WIRE 16 -1 (3050 3700)(2450 3700);
WIRE 16 -1 (3050 3900)(2450 3900);
WIRE 16 -1 (3200 2050)(3825 2050);
WIRE 16 -1 (3200 2100)(3625 2100);
WIRE 16 -1 (3200 2250)(3825 2250);
WIRE 16 -1 (3200 2300)(3625 2300);
WIRE 16 -1 (3200 2450)(3825 2450);
WIRE 16 -1 (3200 2500)(3625 2500);
WIRE 16 -1 (3200 2700)(3625 2700);
WIRE 16 -1 (3200 2650)(3825 2650);
WIRE 16 -1 (3200 2900)(3625 2900);
WIRE 16 -1 (3200 3450)(3825 3450);
WIRE 16 -1 (3200 3500)(3625 3500);
WIRE 16 -1 (3200 3650)(3825 3650);
WIRE 16 -1 (3200 3700)(3625 3700);
WIRE 16 -1 (3200 3850)(3825 3850);
WIRE 16 -1 (3200 3900)(3625 3900);
WIRE 16 -1 (3050 4250)(2200 4250);
WIRE 16 -1 (3050 4050)(2200 4050);
WIRE 16 -1 (3050 4450)(2200 4450);
WIRE 16 -1 (3050 4100)(2450 4100);
WIRE 16 -1 (3050 4300)(2450 4300);
WIRE 16 -1 (3050 4500)(2450 4500);
WIRE 16 -1 (3200 4050)(3825 4050);
WIRE 16 -1 (3200 4100)(3625 4100);
WIRE 16 -1 (3200 4250)(3825 4250);
WIRE 16 -1 (3200 4300)(3625 4300);
WIRE 16 -1 (3200 4450)(3825 4450);
WIRE 16 -1 (3200 4500)(3625 4500);
WIRE 16 -1 (3200 2850)(3825 2850);
WIRE 16 -1 (3200 3100)(3625 3100);
WIRE 16 -1 (3200 3300)(3625 3300);
WIRE 16 -1 (3200 3250)(3825 3250);
WIRE 16 -1 (3200 3050)(3825 3050);
WIRE 16 -1 (3050 2650)(2200 2650);
FORCENOTE
CPU1 PCIE G1 TX
(1650 1075) 0;
DISPLAY LEFT (1650 1075);
DISPLAY 4.148936 (1650 1075);
PAINT WHITE (1650 1075);
FORCENOTE
CPU1 PCIE P4 TX
(1575 -975) 0;
DISPLAY LEFT (1575 -975);
DISPLAY 4.148936 (1575 -975);
PAINT WHITE (1575 -975);
FORCENOTE
CPU1 PCIE P3 TX
(-2825 1075) 0;
DISPLAY LEFT (-2825 1075);
DISPLAY 4.148936 (-2825 1075);
PAINT WHITE (-2825 1075);
FORCENOTE
CPU0 PCIE P4 TX
(-2950 -875) 0;
DISPLAY LEFT (-2950 -875);
DISPLAY 4.148936 (-2950 -875);
PAINT WHITE (-2950 -875);
QUIT
